FILE_TYPE = MACRO_DRAWING;
SET COLOR_WIRE YELLOW;
SET COLOR_PROP ORANGE;
SET COLOR_DOT WHITE;
SET COLOR_ARC YELLOW;
SET COLOR_BODY GREEN;
SET COLOR_NOTE PURPLE;
SET PROP_DISPLAY VALUE;
SET PAGE_NUMBER P219;
FORCEADD UNIVERSAL_GND..1
(-1250 -200);
FORCEPROP 3 LASTPIN (-1250 -150) SIG_NAME GND\g
J 0
(-1240 -140);
DISPLAY 0.659574 (-1240 -140);
PAINT MONO (-1240 -140);
DISPLAY INVISIBLE (-1240 -140);
FORCEPROP 1 LAST HDL_POWER GND
J 1
(-1225 -275);
DISPLAY 0.872340 (-1225 -275);
PAINT GREEN (-1225 -275);
DISPLAY INVISIBLE (-1225 -275);
FORCEPROP 2 LAST ROOM IO_SLOT
J 1
(-1475 -125);
DISPLAY 0.744681 (-1475 -125);
DISPLAY INVISIBLE (-1475 -125);
FORCEPROP 2 LAST CDS_LIB logical_power
J 0
(-1250 -200);
PAINT MONO (-1250 -200);
DISPLAY INVISIBLE (-1250 -200);
FORCEPROP 1 LAST PATH I1
J 0
(-1175 -200);
DISPLAY 0.872340 (-1175 -200);
PAINT AQUA (-1175 -200);
DISPLAY INVISIBLE (-1175 -200);
FORCEADD Q_RES..2
(-700 675);
FORCEPROP 1 LAST PART_NUMBER CS31002FB08
J 0
(-660 550);
DISPLAY 0.510638 (-660 550);
DISPLAY INVISIBLE (-660 550);
FORCEPROP 1 LAST VALUE 10K
J 0
(-655 750);
DISPLAY 0.638298 (-655 750);
FORCEPROP 1 LAST TOLERANCE 1%
J 0
(-655 700);
DISPLAY 0.638298 (-655 700);
FORCEPROP 1 LAST PACK_TYPE 0402LF
J 0
(-660 500);
DISPLAY 0.638298 (-660 500);
FORCEPROP 1 LAST WATTAGE 1/16W
J 0
(-660 650);
DISPLAY 0.638298 (-660 650);
FORCEPROP 1 LAST MATERIAL EMPTY
J 0
(-660 600);
DISPLAY 0.638298 (-660 600);
PAINT RED (-660 600);
FORCEPROP 1 LAST $LOCATION R540
J 0
(-655 800);
DISPLAY 0.978723 (-655 800);
FORCEPROP 1 LASTPIN (-700 775) $PN 1
J 0
(-695 737);
DISPLAY 0.787234 (-695 737);
FORCEPROP 1 LASTPIN (-700 575) $PN 2
J 0
(-695 585);
DISPLAY 0.787234 (-695 585);
FORCEPROP 2 LAST CDS_LIB pure_quanta
J 0
(-700 675);
PAINT MONO (-700 675);
DISPLAY INVISIBLE (-700 675);
FORCEPROP 1 LAST PATH I10
J 0
(-650 850);
DISPLAY 0.978723 (-650 850);
PAINT WHITE (-650 850);
DISPLAY INVISIBLE (-650 850);
FORCEPROP 1 LAST $LOCATION R540
J 0
(-650 900);
DISPLAY 1.021277 (-650 900);
DISPLAY INVISIBLE (-650 900);
FORCEPROP 2 LAST CDS_LOCATION R540
J 0
(-650 900);
DISPLAY 1.021277 (-650 900);
DISPLAY INVISIBLE (-650 900);
FORCEPROP 2 LAST $SEC 1
J 0
(-650 900);
DISPLAY 0.680851 (-650 900);
PAINT MONO (-650 900);
DISPLAY INVISIBLE (-650 900);
FORCEPROP 2 LAST CDS_SEC 1
J 0
(-650 900);
DISPLAY 1.021277 (-650 900);
DISPLAY INVISIBLE (-650 900);
FORCEADD OFFPAGE..1
(-1125 2875);
FORCEPROP 2 LAST $XR0 215 
J 0
(-1377 2875);
DISPLAY 0.638298 (-1377 2875);
PAINT MONO (-1377 2875);
FORCEPROP 2 LAST $XR1 154 
J 0
(-1497 2875);
DISPLAY 0.638298 (-1497 2875);
PAINT MONO (-1497 2875);
FORCEPROP 2 LAST $XR2 161 
J 0
(-1617 2875);
DISPLAY 0.638298 (-1617 2875);
PAINT MONO (-1617 2875);
FORCEPROP 2 LAST $XR3 191 
J 0
(-1737 2875);
DISPLAY 0.638298 (-1737 2875);
PAINT MONO (-1737 2875);
FORCEPROP 2 LAST $XR4 227 
J 0
(-1857 2875);
DISPLAY 0.638298 (-1857 2875);
PAINT MONO (-1857 2875);
FORCEPROP 2 LAST $XR5 233 
J 0
(-1977 2875);
DISPLAY 0.638298 (-1977 2875);
PAINT MONO (-1977 2875);
FORCEPROP 2 LAST $XR6 236 
J 0
(-2097 2875);
DISPLAY 0.638298 (-2097 2875);
PAINT MONO (-2097 2875);
FORCEPROP 2 LAST $XR7 245 
J 0
(-2217 2875);
DISPLAY 0.638298 (-2217 2875);
PAINT MONO (-2217 2875);
FORCEPROP 1 LAST COMMENT_BODY TRUE
J 0
(-1000 2775);
DISPLAY 0.872340 (-1000 2775);
PAINT GREEN (-1000 2775);
DISPLAY INVISIBLE (-1000 2775);
FORCEPROP 1 LAST OFFPAGE TRUE
J 0
(-800 2750);
DISPLAY 0.872340 (-800 2750);
DISPLAY INVISIBLE (-800 2750);
FORCEPROP 2 LAST CDS_LIB standard
J 0
(-1125 2875);
DISPLAY INVISIBLE (-1125 2875);
FORCEPROP 2 LAST PATH I11
J 0
(-1375 2925);
DISPLAY 1.021277 (-1375 2925);
DISPLAY INVISIBLE (-1375 2925);
FORCEADD OFFPAGE..3
R 2
(-600 2425);
FORCEPROP 2 LAST $XR0 231 
J 0
(-880 2425);
DISPLAY 0.638298 (-880 2425);
PAINT MONO (-880 2425);
FORCEPROP 2 LAST $XR1 194 
J 0
(-1000 2425);
DISPLAY 0.638298 (-1000 2425);
PAINT MONO (-1000 2425);
FORCEPROP 1 LAST COMMENT_BODY TRUE
J 2
(-550 2325);
DISPLAY 0.872340 (-550 2325);
PAINT GREEN (-550 2325);
DISPLAY INVISIBLE (-550 2325);
FORCEPROP 1 LAST OFFPAGE TRUE
J 2
(-925 2300);
DISPLAY 0.872340 (-925 2300);
DISPLAY INVISIBLE (-925 2300);
FORCEPROP 2 LAST CDS_LIB standard
J 2
(-600 2425);
DISPLAY INVISIBLE (-600 2425);
FORCEPROP 2 LAST PATH I12
J 0
(-875 2475);
DISPLAY 1.021277 (-875 2475);
DISPLAY INVISIBLE (-875 2475);
FORCEADD OFFPAGE..3
R 2
(-600 2525);
FORCEPROP 2 LAST $XR0 231 
J 0
(-880 2525);
DISPLAY 0.638298 (-880 2525);
PAINT MONO (-880 2525);
FORCEPROP 2 LAST $XR1 194 
J 0
(-1000 2525);
DISPLAY 0.638298 (-1000 2525);
PAINT MONO (-1000 2525);
FORCEPROP 1 LAST COMMENT_BODY TRUE
J 2
(-550 2425);
DISPLAY 0.872340 (-550 2425);
PAINT GREEN (-550 2425);
DISPLAY INVISIBLE (-550 2425);
FORCEPROP 1 LAST OFFPAGE TRUE
J 2
(-925 2400);
DISPLAY 0.872340 (-925 2400);
DISPLAY INVISIBLE (-925 2400);
FORCEPROP 2 LAST CDS_LIB standard
J 2
(-600 2525);
DISPLAY INVISIBLE (-600 2525);
FORCEPROP 2 LAST PATH I13
J 0
(-875 2575);
DISPLAY 1.021277 (-875 2575);
DISPLAY INVISIBLE (-875 2575);
FORCEADD OFFPAGE..5
(-600 2475);
FORCEPROP 2 LAST $XR0 194 
J 0
(-885 2475);
DISPLAY 0.638298 (-885 2475);
PAINT MONO (-885 2475);
FORCEPROP 2 LAST $XR1 231 
J 0
(-1005 2475);
DISPLAY 0.638298 (-1005 2475);
PAINT MONO (-1005 2475);
FORCEPROP 1 LAST COMMENT_BODY TRUE
J 0
(-500 2400);
DISPLAY 0.872340 (-500 2400);
PAINT GREEN (-500 2400);
DISPLAY INVISIBLE (-500 2400);
FORCEPROP 1 LAST OFFPAGE TRUE
J 0
(-275 2350);
DISPLAY 0.872340 (-275 2350);
DISPLAY INVISIBLE (-275 2350);
FORCEPROP 2 LAST CDS_LIB standard
J 2
(-600 2475);
DISPLAY INVISIBLE (-600 2475);
FORCEPROP 2 LAST PATH I14
J 0
(-875 2525);
DISPLAY 1.021277 (-875 2525);
DISPLAY INVISIBLE (-875 2525);
FORCEADD OFFPAGE..3
R 2
(-600 2625);
FORCEPROP 2 LAST $XR0 231 
J 0
(-880 2625);
DISPLAY 0.638298 (-880 2625);
PAINT MONO (-880 2625);
FORCEPROP 2 LAST $XR1 227 
J 0
(-1000 2625);
DISPLAY 0.638298 (-1000 2625);
PAINT MONO (-1000 2625);
FORCEPROP 1 LAST COMMENT_BODY TRUE
J 2
(-550 2525);
DISPLAY 0.872340 (-550 2525);
PAINT GREEN (-550 2525);
DISPLAY INVISIBLE (-550 2525);
FORCEPROP 1 LAST OFFPAGE TRUE
J 2
(-925 2500);
DISPLAY 0.872340 (-925 2500);
DISPLAY INVISIBLE (-925 2500);
FORCEPROP 2 LAST CDS_LIB standard
J 2
(-600 2625);
DISPLAY INVISIBLE (-600 2625);
FORCEPROP 2 LAST PATH I15
J 0
(-875 2675);
DISPLAY 1.021277 (-875 2675);
DISPLAY INVISIBLE (-875 2675);
FORCEADD OFFPAGE..5
(-600 2575);
FORCEPROP 2 LAST $XR0 194 
J 0
(-885 2575);
DISPLAY 0.638298 (-885 2575);
PAINT MONO (-885 2575);
FORCEPROP 2 LAST $XR1 231 
J 0
(-1005 2575);
DISPLAY 0.638298 (-1005 2575);
PAINT MONO (-1005 2575);
FORCEPROP 1 LAST COMMENT_BODY TRUE
J 0
(-500 2500);
DISPLAY 0.872340 (-500 2500);
PAINT GREEN (-500 2500);
DISPLAY INVISIBLE (-500 2500);
FORCEPROP 1 LAST OFFPAGE TRUE
J 0
(-275 2450);
DISPLAY 0.872340 (-275 2450);
DISPLAY INVISIBLE (-275 2450);
FORCEPROP 2 LAST CDS_LIB standard
J 2
(-600 2575);
DISPLAY INVISIBLE (-600 2575);
FORCEPROP 2 LAST PATH I16
J 0
(-875 2625);
DISPLAY 1.021277 (-875 2625);
DISPLAY INVISIBLE (-875 2625);
FORCEADD OFFPAGE..5
(-600 2675);
FORCEPROP 2 LAST $XR0 231 
J 0
(-855 2675);
DISPLAY 0.638298 (-855 2675);
PAINT MONO (-855 2675);
FORCEPROP 2 LAST $XR1 227 
J 0
(-975 2675);
DISPLAY 0.638298 (-975 2675);
PAINT MONO (-975 2675);
FORCEPROP 1 LAST COMMENT_BODY TRUE
J 0
(-500 2600);
DISPLAY 0.872340 (-500 2600);
PAINT GREEN (-500 2600);
DISPLAY INVISIBLE (-500 2600);
FORCEPROP 1 LAST OFFPAGE TRUE
J 0
(-275 2550);
DISPLAY 0.872340 (-275 2550);
DISPLAY INVISIBLE (-275 2550);
FORCEPROP 2 LAST CDS_LIB standard
J 2
(-600 2675);
DISPLAY INVISIBLE (-600 2675);
FORCEPROP 2 LAST PATH I17
J 0
(-850 2725);
DISPLAY 1.021277 (-850 2725);
DISPLAY INVISIBLE (-850 2725);
FORCEADD Q_RES..2
R 2
(-600 3225);
FORCEPROP 1 LAST PART_NUMBER CS31002FB08
J 2
(-640 3050);
DISPLAY 0.638298 (-640 3050);
DISPLAY INVISIBLE (-640 3050);
FORCEPROP 1 LAST VALUE 10K
J 2
(-645 3300);
DISPLAY 0.638298 (-645 3300);
FORCEPROP 1 LAST PACK_TYPE 0402LF
J 2
(-640 3100);
DISPLAY 0.638298 (-640 3100);
FORCEPROP 1 LAST TOLERANCE 1%
J 2
(-645 3250);
DISPLAY 0.638298 (-645 3250);
FORCEPROP 1 LAST WATTAGE 1/16W
J 2
(-640 3200);
DISPLAY 0.638298 (-640 3200);
FORCEPROP 1 LAST MATERIAL CHIP
J 2
(-640 3150);
DISPLAY 0.638298 (-640 3150);
FORCEPROP 1 LAST $LOCATION R1822
J 2
(-645 3350);
DISPLAY 0.978723 (-645 3350);
FORCEPROP 1 LASTPIN (-600 3325) $PN 1
J 2
(-605 3287);
DISPLAY 0.787234 (-605 3287);
FORCEPROP 1 LASTPIN (-600 3125) $PN 2
J 2
(-605 3135);
DISPLAY 0.787234 (-605 3135);
FORCEPROP 2 LAST CDS_LIB pure_quanta
J 2
(-600 3225);
PAINT MONO (-600 3225);
DISPLAY INVISIBLE (-600 3225);
FORCEPROP 1 LAST PATH I18
J 2
(-650 3400);
DISPLAY 0.978723 (-650 3400);
PAINT WHITE (-650 3400);
DISPLAY INVISIBLE (-650 3400);
FORCEPROP 2 LAST CDS_LOCATION R1822
J 0
(-650 3450);
DISPLAY 1.021277 (-650 3450);
DISPLAY INVISIBLE (-650 3450);
FORCEPROP 2 LAST $SEC 1
J 0
(-650 3450);
DISPLAY 0.680851 (-650 3450);
PAINT MONO (-650 3450);
DISPLAY INVISIBLE (-650 3450);
FORCEPROP 2 LAST CDS_SEC 1
J 0
(-650 3450);
DISPLAY 1.021277 (-650 3450);
DISPLAY INVISIBLE (-650 3450);
FORCEADD UNIVERSAL_POWER..1
(-600 3500);
FORCEPROP 3 LASTPIN (-600 3450) SIG_NAME P3V3_AUX\g
J 0
(-590 3460);
DISPLAY 0.659574 (-590 3460);
PAINT MONO (-590 3460);
DISPLAY INVISIBLE (-590 3460);
FORCEPROP 1 LAST HDL_POWER P3V3_AUX
J 1
(-600 3550);
DISPLAY 0.872340 (-600 3550);
PAINT GREEN (-600 3550);
FORCEPROP 2 LAST CDS_LIB logical_power
J 0
(-600 3500);
DISPLAY INVISIBLE (-600 3500);
FORCEPROP 1 LAST PATH I19
J 0
(-550 3525);
DISPLAY 0.872340 (-550 3525);
PAINT AQUA (-550 3525);
DISPLAY INVISIBLE (-550 3525);
FORCEADD Q_RES..2
(-1250 25);
FORCEPROP 1 LAST PART_NUMBER CS21002FB06
J 0
(-1210 -100);
DISPLAY 0.510638 (-1210 -100);
DISPLAY INVISIBLE (-1210 -100);
FORCEPROP 1 LAST TOLERANCE 1%
J 0
(-1205 50);
DISPLAY 0.638298 (-1205 50);
FORCEPROP 1 LAST WATTAGE 1/16W
J 0
(-1210 0);
DISPLAY 0.638298 (-1210 0);
FORCEPROP 1 LAST MATERIAL CHIP
J 0
(-1210 -50);
DISPLAY 0.638298 (-1210 -50);
FORCEPROP 1 LAST PACK_TYPE 0402LF
J 0
(-1210 -100);
DISPLAY 0.638298 (-1210 -100);
FORCEPROP 1 LAST VALUE 1K
J 0
(-1205 100);
DISPLAY 0.638298 (-1205 100);
FORCEPROP 1 LAST $LOCATION R537
J 0
(-1205 150);
DISPLAY 0.978723 (-1205 150);
FORCEPROP 1 LASTPIN (-1250 125) $PN 1
J 0
(-1245 87);
DISPLAY 0.787234 (-1245 87);
FORCEPROP 1 LASTPIN (-1250 -75) $PN 2
J 0
(-1245 -65);
DISPLAY 0.787234 (-1245 -65);
FORCEPROP 2 LAST CDS_LIB pure_quanta
J 0
(-1250 25);
PAINT MONO (-1250 25);
DISPLAY INVISIBLE (-1250 25);
FORCEPROP 1 LAST PATH I2
J 0
(-1200 200);
DISPLAY 0.978723 (-1200 200);
PAINT WHITE (-1200 200);
DISPLAY INVISIBLE (-1200 200);
FORCEPROP 1 LAST $LOCATION R537
J 0
(-1200 250);
DISPLAY 1.021277 (-1200 250);
DISPLAY INVISIBLE (-1200 250);
FORCEPROP 2 LAST CDS_LOCATION R537
J 0
(-1200 250);
DISPLAY 1.021277 (-1200 250);
DISPLAY INVISIBLE (-1200 250);
FORCEPROP 2 LAST $SEC 1
J 0
(-1200 250);
DISPLAY 0.680851 (-1200 250);
PAINT MONO (-1200 250);
DISPLAY INVISIBLE (-1200 250);
FORCEPROP 2 LAST CDS_SEC 1
J 0
(-1200 250);
DISPLAY 1.021277 (-1200 250);
DISPLAY INVISIBLE (-1200 250);
FORCEADD Q_RES..1
(3875 -1275);
FORCEPROP 1 LAST PART_NUMBER CS22202JB07
J 0
(3775 -1225);
DISPLAY 0.510638 (3775 -1225);
DISPLAY INVISIBLE (3775 -1225);
FORCEPROP 1 LAST MATERIAL CHIP
J 0
(4175 -1275);
DISPLAY 0.510638 (4175 -1275);
FORCEPROP 1 LAST VALUE 2.2K
J 2
(4100 -1275);
DISPLAY 0.510638 (4100 -1275);
FORCEPROP 1 LAST TOLERANCE 5%
J 0
(4100 -1275);
DISPLAY 0.510638 (4100 -1275);
FORCEPROP 1 LAST $LOCATION R1090
J 0
(3625 -1275);
DISPLAY 0.510638 (3625 -1275);
FORCEPROP 1 LASTPIN (3775 -1275) $PN 1
J 0
(3787 -1263);
DISPLAY 0.787234 (3787 -1263);
FORCEPROP 1 LASTPIN (3975 -1275) $PN 2
J 0
(3937 -1263);
DISPLAY 0.787234 (3937 -1263);
FORCEPROP 1 LAST WATTAGE 1/16W
J 2
(4075 -1175);
DISPLAY 0.510638 (4075 -1175);
DISPLAY INVISIBLE (4075 -1175);
FORCEPROP 1 LAST PACK_TYPE 0402LF
J 0
(3775 -1175);
DISPLAY 0.510638 (3775 -1175);
DISPLAY INVISIBLE (3775 -1175);
FORCEPROP 2 LAST CDS_LIB pure_quanta
J 0
(3875 -1275);
PAINT MONO (3875 -1275);
DISPLAY INVISIBLE (3875 -1275);
FORCEPROP 1 LAST PATH I20
J 0
(3825 -1125);
DISPLAY 0.978723 (3825 -1125);
PAINT WHITE (3825 -1125);
DISPLAY INVISIBLE (3825 -1125);
FORCEPROP 2 LAST CDS_LOCATION R1090
J 0
(3825 -1075);
DISPLAY 1.021277 (3825 -1075);
DISPLAY INVISIBLE (3825 -1075);
FORCEPROP 2 LAST $SEC 1
J 0
(3825 -1075);
DISPLAY 0.680851 (3825 -1075);
PAINT MONO (3825 -1075);
DISPLAY INVISIBLE (3825 -1075);
FORCEPROP 2 LAST CDS_SEC 1
J 0
(3825 -1075);
DISPLAY 1.021277 (3825 -1075);
DISPLAY INVISIBLE (3825 -1075);
FORCEADD Q_RES..1
(3875 -1225);
FORCEPROP 1 LAST PART_NUMBER CS22202JB07
J 0
(3725 -1150);
DISPLAY 0.510638 (3725 -1150);
DISPLAY INVISIBLE (3725 -1150);
FORCEPROP 1 LAST WATTAGE 1/16W
J 2
(4025 -1100);
DISPLAY 0.510638 (4025 -1100);
FORCEPROP 1 LAST VALUE 2.2K
J 2
(4100 -1225);
DISPLAY 0.510638 (4100 -1225);
FORCEPROP 1 LAST TOLERANCE 5%
J 0
(4100 -1225);
DISPLAY 0.510638 (4100 -1225);
FORCEPROP 1 LAST MATERIAL CHIP
J 0
(4175 -1225);
DISPLAY 0.510638 (4175 -1225);
FORCEPROP 1 LAST PACK_TYPE 0402LF
J 0
(3725 -1100);
DISPLAY 0.510638 (3725 -1100);
FORCEPROP 1 LAST $LOCATION R1089
J 0
(3625 -1225);
DISPLAY 0.510638 (3625 -1225);
FORCEPROP 1 LASTPIN (3775 -1225) $PN 1
J 0
(3787 -1213);
DISPLAY 0.787234 (3787 -1213);
FORCEPROP 1 LASTPIN (3975 -1225) $PN 2
J 0
(3937 -1213);
DISPLAY 0.787234 (3937 -1213);
FORCEPROP 2 LAST CDS_LIB pure_quanta
J 0
(3875 -1225);
PAINT MONO (3875 -1225);
DISPLAY INVISIBLE (3875 -1225);
FORCEPROP 1 LAST PATH I21
J 0
(3825 -1075);
DISPLAY 0.978723 (3825 -1075);
PAINT WHITE (3825 -1075);
DISPLAY INVISIBLE (3825 -1075);
FORCEPROP 2 LAST CDS_LOCATION R1089
J 0
(3825 -1025);
DISPLAY 1.021277 (3825 -1025);
DISPLAY INVISIBLE (3825 -1025);
FORCEPROP 2 LAST $SEC 1
J 0
(3825 -1025);
DISPLAY 0.680851 (3825 -1025);
PAINT MONO (3825 -1025);
DISPLAY INVISIBLE (3825 -1025);
FORCEPROP 2 LAST CDS_SEC 1
J 0
(3825 -1025);
DISPLAY 1.021277 (3825 -1025);
DISPLAY INVISIBLE (3825 -1025);
FORCEADD Q_RES..1
(3875 -900);
FORCEPROP 1 LAST PART_NUMBER CS22202JB07
J 0
(3725 -825);
DISPLAY 0.510638 (3725 -825);
DISPLAY INVISIBLE (3725 -825);
FORCEPROP 1 LAST PACK_TYPE 0402LF
J 0
(3725 -775);
DISPLAY 0.510638 (3725 -775);
FORCEPROP 1 LAST VALUE 2.2K
J 2
(4100 -900);
DISPLAY 0.510638 (4100 -900);
FORCEPROP 1 LAST TOLERANCE 5%
J 0
(4100 -900);
DISPLAY 0.510638 (4100 -900);
FORCEPROP 1 LAST WATTAGE 1/16W
J 2
(4025 -775);
DISPLAY 0.510638 (4025 -775);
FORCEPROP 1 LAST MATERIAL CHIP
J 0
(4175 -900);
DISPLAY 0.510638 (4175 -900);
FORCEPROP 1 LAST $LOCATION R651
J 0
(3625 -900);
DISPLAY 0.510638 (3625 -900);
FORCEPROP 1 LASTPIN (3775 -900) $PN 1
J 0
(3787 -888);
DISPLAY 0.787234 (3787 -888);
FORCEPROP 1 LASTPIN (3975 -900) $PN 2
J 0
(3937 -888);
DISPLAY 0.787234 (3937 -888);
FORCEPROP 2 LAST CDS_LIB pure_quanta
J 0
(3875 -900);
PAINT MONO (3875 -900);
DISPLAY INVISIBLE (3875 -900);
FORCEPROP 1 LAST PATH I22
J 0
(3825 -750);
DISPLAY 0.978723 (3825 -750);
PAINT WHITE (3825 -750);
DISPLAY INVISIBLE (3825 -750);
FORCEPROP 2 LAST CDS_LOCATION R651
J 0
(3825 -700);
DISPLAY 1.021277 (3825 -700);
DISPLAY INVISIBLE (3825 -700);
FORCEPROP 2 LAST $SEC 1
J 0
(3825 -700);
DISPLAY 0.680851 (3825 -700);
PAINT MONO (3825 -700);
DISPLAY INVISIBLE (3825 -700);
FORCEPROP 2 LAST CDS_SEC 1
J 0
(3825 -700);
DISPLAY 1.021277 (3825 -700);
DISPLAY INVISIBLE (3825 -700);
FORCEADD Q_RES..1
(3875 -950);
FORCEPROP 1 LAST PART_NUMBER CS22202JB07
J 0
(3775 -900);
DISPLAY 0.510638 (3775 -900);
DISPLAY INVISIBLE (3775 -900);
FORCEPROP 1 LAST TOLERANCE 5%
J 0
(4100 -950);
DISPLAY 0.510638 (4100 -950);
FORCEPROP 1 LAST VALUE 2.2K
J 2
(4100 -950);
DISPLAY 0.510638 (4100 -950);
FORCEPROP 1 LAST MATERIAL CHIP
J 0
(4175 -950);
DISPLAY 0.510638 (4175 -950);
FORCEPROP 1 LAST $LOCATION R652
J 0
(3625 -950);
DISPLAY 0.510638 (3625 -950);
FORCEPROP 1 LASTPIN (3775 -950) $PN 1
J 0
(3787 -938);
DISPLAY 0.787234 (3787 -938);
FORCEPROP 1 LASTPIN (3975 -950) $PN 2
J 0
(3937 -938);
DISPLAY 0.787234 (3937 -938);
FORCEPROP 2 LAST CDS_LIB pure_quanta
J 0
(3875 -950);
PAINT MONO (3875 -950);
DISPLAY INVISIBLE (3875 -950);
FORCEPROP 1 LAST PACK_TYPE 0402LF
J 0
(3775 -850);
DISPLAY 0.510638 (3775 -850);
DISPLAY INVISIBLE (3775 -850);
FORCEPROP 1 LAST WATTAGE 1/16W
J 2
(4075 -850);
DISPLAY 0.510638 (4075 -850);
DISPLAY INVISIBLE (4075 -850);
FORCEPROP 1 LAST PATH I23
J 0
(3825 -800);
DISPLAY 0.978723 (3825 -800);
PAINT WHITE (3825 -800);
DISPLAY INVISIBLE (3825 -800);
FORCEPROP 2 LAST CDS_LOCATION R652
J 0
(3825 -750);
DISPLAY 1.021277 (3825 -750);
DISPLAY INVISIBLE (3825 -750);
FORCEPROP 2 LAST $SEC 1
J 0
(3825 -750);
DISPLAY 0.680851 (3825 -750);
PAINT MONO (3825 -750);
DISPLAY INVISIBLE (3825 -750);
FORCEPROP 2 LAST CDS_SEC 1
J 0
(3825 -750);
DISPLAY 1.021277 (3825 -750);
DISPLAY INVISIBLE (3825 -750);
FORCEADD Q_RES..1
(3875 -625);
FORCEPROP 1 LAST PART_NUMBER CS31002FB08
J 0
(3775 -575);
DISPLAY 0.510638 (3775 -575);
DISPLAY INVISIBLE (3775 -575);
FORCEPROP 1 LAST VALUE 10K
J 2
(4100 -625);
DISPLAY 0.510638 (4100 -625);
FORCEPROP 1 LAST MATERIAL CHIP
J 0
(4175 -625);
DISPLAY 0.510638 (4175 -625);
FORCEPROP 1 LAST TOLERANCE 1%
J 0
(4100 -625);
DISPLAY 0.510638 (4100 -625);
FORCEPROP 1 LAST $LOCATION R2985
J 0
(3625 -625);
DISPLAY 0.510638 (3625 -625);
FORCEPROP 1 LASTPIN (3775 -625) $PN 1
J 0
(3787 -613);
DISPLAY 0.787234 (3787 -613);
FORCEPROP 1 LASTPIN (3975 -625) $PN 2
J 0
(3937 -613);
DISPLAY 0.787234 (3937 -613);
FORCEPROP 2 LAST CDS_LIB pure_quanta
J 0
(3875 -625);
PAINT MONO (3875 -625);
DISPLAY INVISIBLE (3875 -625);
FORCEPROP 1 LAST PACK_TYPE 0402LF
J 0
(3775 -525);
DISPLAY 0.510638 (3775 -525);
DISPLAY INVISIBLE (3775 -525);
FORCEPROP 1 LAST WATTAGE 1/16W
J 2
(4075 -525);
DISPLAY 0.510638 (4075 -525);
DISPLAY INVISIBLE (4075 -525);
FORCEPROP 1 LAST PATH I24
J 0
(3825 -475);
DISPLAY 0.978723 (3825 -475);
PAINT WHITE (3825 -475);
DISPLAY INVISIBLE (3825 -475);
FORCEPROP 2 LAST CDS_LOCATION R2985
J 0
(3825 -425);
DISPLAY 1.021277 (3825 -425);
DISPLAY INVISIBLE (3825 -425);
FORCEPROP 2 LAST $SEC 1
J 0
(3825 -425);
DISPLAY 0.680851 (3825 -425);
PAINT MONO (3825 -425);
DISPLAY INVISIBLE (3825 -425);
FORCEPROP 2 LAST CDS_SEC 1
J 0
(3825 -425);
DISPLAY 1.021277 (3825 -425);
DISPLAY INVISIBLE (3825 -425);
FORCEADD Q_RES..1
(3875 -575);
FORCEPROP 1 LAST PART_NUMBER CS31002FB08
J 0
(3725 -500);
DISPLAY 0.510638 (3725 -500);
DISPLAY INVISIBLE (3725 -500);
FORCEPROP 1 LAST WATTAGE 1/16W
J 2
(4025 -450);
DISPLAY 0.510638 (4025 -450);
FORCEPROP 1 LAST PACK_TYPE 0402LF
J 0
(3725 -450);
DISPLAY 0.510638 (3725 -450);
FORCEPROP 1 LAST MATERIAL CHIP
J 0
(4175 -575);
DISPLAY 0.510638 (4175 -575);
FORCEPROP 1 LAST VALUE 10K
J 2
(4100 -575);
DISPLAY 0.510638 (4100 -575);
FORCEPROP 1 LAST TOLERANCE 1%
J 0
(4100 -575);
DISPLAY 0.510638 (4100 -575);
FORCEPROP 1 LAST $LOCATION R2984
J 0
(3625 -575);
DISPLAY 0.510638 (3625 -575);
FORCEPROP 1 LASTPIN (3775 -575) $PN 1
J 0
(3787 -563);
DISPLAY 0.787234 (3787 -563);
FORCEPROP 1 LASTPIN (3975 -575) $PN 2
J 0
(3937 -563);
DISPLAY 0.787234 (3937 -563);
FORCEPROP 2 LAST CDS_LIB pure_quanta
J 0
(3875 -575);
PAINT MONO (3875 -575);
DISPLAY INVISIBLE (3875 -575);
FORCEPROP 1 LAST PATH I25
J 0
(3825 -425);
DISPLAY 0.978723 (3825 -425);
PAINT WHITE (3825 -425);
DISPLAY INVISIBLE (3825 -425);
FORCEPROP 2 LAST CDS_LOCATION R2984
J 0
(3825 -375);
DISPLAY 1.021277 (3825 -375);
DISPLAY INVISIBLE (3825 -375);
FORCEPROP 2 LAST $SEC 1
J 0
(3825 -375);
DISPLAY 0.680851 (3825 -375);
PAINT MONO (3825 -375);
DISPLAY INVISIBLE (3825 -375);
FORCEPROP 2 LAST CDS_SEC 1
J 0
(3825 -375);
DISPLAY 1.021277 (3825 -375);
DISPLAY INVISIBLE (3825 -375);
FORCEADD OFFPAGE..2
(5275 -1275);
FORCEPROP 2 LAST $XR0 194 
J 0
(5464 -1275);
DISPLAY 0.638298 (5464 -1275);
PAINT MONO (5464 -1275);
FORCEPROP 2 LAST $XR1 231 
J 0
(5584 -1275);
DISPLAY 0.638298 (5584 -1275);
PAINT MONO (5584 -1275);
FORCEPROP 1 LAST COMMENT_BODY TRUE
J 0
(5230 -1370);
DISPLAY 0.872340 (5230 -1370);
PAINT GREEN (5230 -1370);
DISPLAY INVISIBLE (5230 -1370);
FORCEPROP 1 LAST OFFPAGE TRUE
J 0
(5600 -1400);
DISPLAY 0.872340 (5600 -1400);
PAINT GREEN (5600 -1400);
DISPLAY INVISIBLE (5600 -1400);
FORCEPROP 2 LAST CDS_LIB standard
J 0
(5275 -1275);
PAINT MONO (5275 -1275);
DISPLAY INVISIBLE (5275 -1275);
FORCEPROP 2 LAST PATH I26
J 0
(5600 -1225);
DISPLAY 1.021277 (5600 -1225);
DISPLAY INVISIBLE (5600 -1225);
FORCEADD OFFPAGE..2
(5275 -1225);
FORCEPROP 2 LAST $XR0 231 
J 0
(5464 -1225);
DISPLAY 0.638298 (5464 -1225);
PAINT MONO (5464 -1225);
FORCEPROP 2 LAST $XR1 194 
J 0
(5584 -1225);
DISPLAY 0.638298 (5584 -1225);
PAINT MONO (5584 -1225);
FORCEPROP 1 LAST COMMENT_BODY TRUE
J 0
(5230 -1320);
DISPLAY 0.872340 (5230 -1320);
PAINT GREEN (5230 -1320);
DISPLAY INVISIBLE (5230 -1320);
FORCEPROP 1 LAST OFFPAGE TRUE
J 0
(5600 -1350);
DISPLAY 0.872340 (5600 -1350);
PAINT GREEN (5600 -1350);
DISPLAY INVISIBLE (5600 -1350);
FORCEPROP 2 LAST CDS_LIB standard
J 0
(5275 -1225);
PAINT MONO (5275 -1225);
DISPLAY INVISIBLE (5275 -1225);
FORCEPROP 2 LAST PATH I27
J 0
(5600 -1175);
DISPLAY 1.021277 (5600 -1175);
DISPLAY INVISIBLE (5600 -1175);
FORCEADD OFFPAGE..2
(5275 -950);
FORCEPROP 2 LAST $XR0 231 
J 0
(5464 -950);
DISPLAY 0.638298 (5464 -950);
PAINT MONO (5464 -950);
FORCEPROP 2 LAST $XR1 243 
J 0
(5584 -950);
DISPLAY 0.638298 (5584 -950);
PAINT MONO (5584 -950);
FORCEPROP 1 LAST COMMENT_BODY TRUE
J 0
(5230 -1045);
DISPLAY 0.872340 (5230 -1045);
PAINT GREEN (5230 -1045);
DISPLAY INVISIBLE (5230 -1045);
FORCEPROP 1 LAST OFFPAGE TRUE
J 0
(5600 -1075);
DISPLAY 0.872340 (5600 -1075);
PAINT GREEN (5600 -1075);
DISPLAY INVISIBLE (5600 -1075);
FORCEPROP 2 LAST CDS_LIB standard
J 0
(5275 -950);
PAINT MONO (5275 -950);
DISPLAY INVISIBLE (5275 -950);
FORCEPROP 2 LAST PATH I28
J 0
(5600 -900);
DISPLAY 1.021277 (5600 -900);
DISPLAY INVISIBLE (5600 -900);
FORCEADD OFFPAGE..2
(5275 -900);
FORCEPROP 2 LAST $XR0 231 
J 0
(5464 -900);
DISPLAY 0.638298 (5464 -900);
PAINT MONO (5464 -900);
FORCEPROP 2 LAST $XR1 243 
J 0
(5584 -900);
DISPLAY 0.638298 (5584 -900);
PAINT MONO (5584 -900);
FORCEPROP 1 LAST COMMENT_BODY TRUE
J 0
(5230 -995);
DISPLAY 0.872340 (5230 -995);
PAINT GREEN (5230 -995);
DISPLAY INVISIBLE (5230 -995);
FORCEPROP 1 LAST OFFPAGE TRUE
J 0
(5600 -1025);
DISPLAY 0.872340 (5600 -1025);
PAINT GREEN (5600 -1025);
DISPLAY INVISIBLE (5600 -1025);
FORCEPROP 2 LAST CDS_LIB standard
J 0
(5275 -900);
PAINT MONO (5275 -900);
DISPLAY INVISIBLE (5275 -900);
FORCEPROP 2 LAST PATH I29
J 0
(5600 -850);
DISPLAY 1.021277 (5600 -850);
DISPLAY INVISIBLE (5600 -850);
FORCEADD Q_RES..2
(-1250 675);
FORCEPROP 1 LAST PART_NUMBER CS31002FB08
J 0
(-1210 550);
DISPLAY 0.510638 (-1210 550);
DISPLAY INVISIBLE (-1210 550);
FORCEPROP 1 LAST WATTAGE 1/16W
J 0
(-1210 650);
DISPLAY 0.638298 (-1210 650);
FORCEPROP 1 LAST VALUE 10K
J 0
(-1205 750);
DISPLAY 0.638298 (-1205 750);
FORCEPROP 1 LAST PACK_TYPE 0402LF
J 0
(-1210 550);
DISPLAY 0.638298 (-1210 550);
FORCEPROP 1 LAST TOLERANCE 1%
J 0
(-1205 700);
DISPLAY 0.638298 (-1205 700);
FORCEPROP 1 LAST MATERIAL EMPTY
J 0
(-1210 600);
DISPLAY 0.638298 (-1210 600);
PAINT RED (-1210 600);
FORCEPROP 1 LAST $LOCATION R536
J 0
(-1205 800);
DISPLAY 0.978723 (-1205 800);
FORCEPROP 1 LASTPIN (-1250 775) $PN 1
J 0
(-1245 737);
DISPLAY 0.787234 (-1245 737);
FORCEPROP 1 LASTPIN (-1250 575) $PN 2
J 0
(-1245 585);
DISPLAY 0.787234 (-1245 585);
FORCEPROP 2 LAST CDS_LIB pure_quanta
J 0
(-1250 675);
PAINT MONO (-1250 675);
DISPLAY INVISIBLE (-1250 675);
FORCEPROP 1 LAST PATH I3
J 0
(-1200 850);
DISPLAY 0.978723 (-1200 850);
PAINT WHITE (-1200 850);
DISPLAY INVISIBLE (-1200 850);
FORCEPROP 1 LAST $LOCATION R536
J 0
(-1200 900);
DISPLAY 1.021277 (-1200 900);
DISPLAY INVISIBLE (-1200 900);
FORCEPROP 2 LAST CDS_LOCATION R536
J 0
(-1200 900);
DISPLAY 1.021277 (-1200 900);
DISPLAY INVISIBLE (-1200 900);
FORCEPROP 2 LAST $SEC 1
J 0
(-1200 900);
DISPLAY 0.680851 (-1200 900);
PAINT MONO (-1200 900);
DISPLAY INVISIBLE (-1200 900);
FORCEPROP 2 LAST CDS_SEC 1
J 0
(-1200 900);
DISPLAY 1.021277 (-1200 900);
DISPLAY INVISIBLE (-1200 900);
FORCEADD OFFPAGE..2
(5275 -625);
FORCEPROP 2 LAST $XR0 231 
J 0
(5464 -625);
DISPLAY 0.638298 (5464 -625);
PAINT MONO (5464 -625);
FORCEPROP 2 LAST $XR1 234 
J 0
(5584 -625);
DISPLAY 0.638298 (5584 -625);
PAINT MONO (5584 -625);
FORCEPROP 1 LAST COMMENT_BODY TRUE
J 0
(5230 -720);
DISPLAY 0.872340 (5230 -720);
PAINT GREEN (5230 -720);
DISPLAY INVISIBLE (5230 -720);
FORCEPROP 1 LAST OFFPAGE TRUE
J 0
(5600 -750);
DISPLAY 0.872340 (5600 -750);
PAINT GREEN (5600 -750);
DISPLAY INVISIBLE (5600 -750);
FORCEPROP 2 LAST CDS_LIB standard
J 0
(5275 -625);
PAINT MONO (5275 -625);
DISPLAY INVISIBLE (5275 -625);
FORCEPROP 2 LAST PATH I30
J 0
(5600 -575);
DISPLAY 1.021277 (5600 -575);
DISPLAY INVISIBLE (5600 -575);
FORCEADD OFFPAGE..2
(5275 -575);
FORCEPROP 2 LAST $XR0 231 
J 0
(5464 -575);
DISPLAY 0.638298 (5464 -575);
PAINT MONO (5464 -575);
FORCEPROP 2 LAST $XR1 234 
J 0
(5584 -575);
DISPLAY 0.638298 (5584 -575);
PAINT MONO (5584 -575);
FORCEPROP 1 LAST COMMENT_BODY TRUE
J 0
(5230 -670);
DISPLAY 0.872340 (5230 -670);
PAINT GREEN (5230 -670);
DISPLAY INVISIBLE (5230 -670);
FORCEPROP 1 LAST OFFPAGE TRUE
J 0
(5600 -700);
DISPLAY 0.872340 (5600 -700);
PAINT GREEN (5600 -700);
DISPLAY INVISIBLE (5600 -700);
FORCEPROP 2 LAST CDS_LIB standard
J 0
(5275 -575);
PAINT MONO (5275 -575);
DISPLAY INVISIBLE (5275 -575);
FORCEPROP 2 LAST PATH I31
J 0
(5600 -525);
DISPLAY 1.021277 (5600 -525);
DISPLAY INVISIBLE (5600 -525);
FORCEADD OFFPAGE..2
(425 250);
FORCEPROP 2 LAST $XR0 231 
J 0
(614 250);
DISPLAY 0.638298 (614 250);
PAINT MONO (614 250);
FORCEPROP 1 LAST COMMENT_BODY TRUE
J 0
(380 155);
DISPLAY 0.872340 (380 155);
PAINT GREEN (380 155);
DISPLAY INVISIBLE (380 155);
FORCEPROP 1 LAST OFFPAGE TRUE
J 0
(750 125);
DISPLAY 0.872340 (750 125);
DISPLAY INVISIBLE (750 125);
FORCEPROP 2 LAST CDS_LIB standard
J 0
(425 250);
PAINT MONO (425 250);
DISPLAY INVISIBLE (425 250);
FORCEPROP 2 LAST PATH I32
J 0
(625 300);
DISPLAY 1.021277 (625 300);
DISPLAY INVISIBLE (625 300);
FORCEADD OFFPAGE..2
(425 325);
FORCEPROP 2 LAST $XR0 231 
J 0
(614 325);
DISPLAY 0.638298 (614 325);
PAINT MONO (614 325);
FORCEPROP 1 LAST COMMENT_BODY TRUE
J 0
(380 230);
DISPLAY 0.872340 (380 230);
PAINT GREEN (380 230);
DISPLAY INVISIBLE (380 230);
FORCEPROP 1 LAST OFFPAGE TRUE
J 0
(750 200);
DISPLAY 0.872340 (750 200);
DISPLAY INVISIBLE (750 200);
FORCEPROP 2 LAST CDS_LIB standard
J 0
(425 325);
PAINT MONO (425 325);
DISPLAY INVISIBLE (425 325);
FORCEPROP 2 LAST PATH I33
J 0
(625 375);
DISPLAY 1.021277 (625 375);
DISPLAY INVISIBLE (625 375);
FORCEADD OFFPAGE..2
(425 400);
FORCEPROP 2 LAST $XR0 231 
J 0
(614 400);
DISPLAY 0.638298 (614 400);
PAINT MONO (614 400);
FORCEPROP 1 LAST COMMENT_BODY TRUE
J 0
(380 305);
DISPLAY 0.872340 (380 305);
PAINT GREEN (380 305);
DISPLAY INVISIBLE (380 305);
FORCEPROP 1 LAST OFFPAGE TRUE
J 0
(750 275);
DISPLAY 0.872340 (750 275);
DISPLAY INVISIBLE (750 275);
FORCEPROP 2 LAST CDS_LIB standard
J 0
(425 400);
PAINT MONO (425 400);
DISPLAY INVISIBLE (425 400);
FORCEPROP 2 LAST PATH I34
J 0
(625 450);
DISPLAY 1.021277 (625 450);
DISPLAY INVISIBLE (625 450);
FORCEADD Q_RES..1
R 2
(600 2425);
FORCEPROP 1 LAST PART_NUMBER CS00002JB13
J 2
(675 2375);
DISPLAY 0.319149 (675 2375);
DISPLAY INVISIBLE (675 2375);
FORCEPROP 1 LAST MATERIAL CHIP
J 2
(350 2425);
DISPLAY 0.510638 (350 2425);
FORCEPROP 1 LAST TOLERANCE 5%
J 2
(425 2425);
DISPLAY 0.510638 (425 2425);
FORCEPROP 1 LAST VALUE 0
J 0
(450 2425);
DISPLAY 0.510638 (450 2425);
FORCEPROP 1 LAST $LOCATION R3526
J 2
(825 2425);
DISPLAY 0.510638 (825 2425);
FORCEPROP 2 LAST CDS_LIB pure_quanta
J 2
(600 2425);
DISPLAY INVISIBLE (600 2425);
FORCEPROP 1 LAST WATTAGE 1/16W
J 0
(500 2350);
DISPLAY 0.319149 (500 2350);
DISPLAY INVISIBLE (500 2350);
FORCEPROP 1 LAST PACK_TYPE 0402LF
J 2
(350 2425);
DISPLAY 0.510638 (350 2425);
DISPLAY INVISIBLE (350 2425);
FORCEPROP 1 LAST PATH I35
J 2
(650 2575);
DISPLAY 0.978723 (650 2575);
PAINT WHITE (650 2575);
DISPLAY INVISIBLE (650 2575);
FORCEPROP 0 LAST CDS_LOCATION R3526
J 2
(825 2475);
DISPLAY INVISIBLE (825 2475);
FORCEPROP 0 LAST $SEC 1
J 2
(825 2475);
DISPLAY INVISIBLE (825 2475);
FORCEPROP 0 LAST CDS_SEC 1
J 2
(825 2475);
DISPLAY INVISIBLE (825 2475);
FORCEPROP 1 LASTPIN (700 2425) $PN 1
J 2
(688 2437);
DISPLAY 0.787234 (688 2437);
PAINT MONO (688 2437);
DISPLAY INVISIBLE (688 2437);
FORCEPROP 1 LASTPIN (500 2425) $PN 2
J 2
(538 2437);
DISPLAY 0.787234 (538 2437);
PAINT MONO (538 2437);
DISPLAY INVISIBLE (538 2437);
FORCEADD Q_RES..1
R 2
(600 2525);
FORCEPROP 1 LAST PART_NUMBER CS00002JB13
J 2
(675 2475);
DISPLAY 0.319149 (675 2475);
DISPLAY INVISIBLE (675 2475);
FORCEPROP 1 LAST VALUE 0
J 0
(450 2525);
DISPLAY 0.510638 (450 2525);
FORCEPROP 1 LAST TOLERANCE 5%
J 2
(425 2525);
DISPLAY 0.510638 (425 2525);
FORCEPROP 1 LAST MATERIAL CHIP
J 2
(350 2525);
DISPLAY 0.510638 (350 2525);
FORCEPROP 1 LAST $LOCATION R2967
J 2
(825 2525);
DISPLAY 0.510638 (825 2525);
FORCEPROP 2 LAST CDS_LIB pure_quanta
J 2
(600 2525);
DISPLAY INVISIBLE (600 2525);
FORCEPROP 1 LAST WATTAGE 1/16W
J 0
(500 2450);
DISPLAY 0.319149 (500 2450);
DISPLAY INVISIBLE (500 2450);
FORCEPROP 1 LAST PACK_TYPE 0402LF
J 2
(350 2525);
DISPLAY 0.510638 (350 2525);
DISPLAY INVISIBLE (350 2525);
FORCEPROP 1 LAST PATH I36
J 2
(650 2675);
DISPLAY 0.978723 (650 2675);
PAINT WHITE (650 2675);
DISPLAY INVISIBLE (650 2675);
FORCEPROP 0 LAST CDS_LOCATION R2967
J 2
(825 2575);
DISPLAY INVISIBLE (825 2575);
FORCEPROP 0 LAST $SEC 1
J 2
(825 2575);
DISPLAY INVISIBLE (825 2575);
FORCEPROP 0 LAST CDS_SEC 1
J 2
(825 2575);
DISPLAY INVISIBLE (825 2575);
FORCEPROP 1 LASTPIN (700 2525) $PN 1
J 2
(688 2537);
DISPLAY 0.787234 (688 2537);
PAINT MONO (688 2537);
DISPLAY INVISIBLE (688 2537);
FORCEPROP 1 LASTPIN (500 2525) $PN 2
J 2
(538 2537);
DISPLAY 0.787234 (538 2537);
PAINT MONO (538 2537);
DISPLAY INVISIBLE (538 2537);
FORCEADD Q_RES..1
R 2
(600 2475);
FORCEPROP 1 LAST PART_NUMBER CS00002JB13
J 2
(700 2425);
DISPLAY 0.510638 (700 2425);
DISPLAY INVISIBLE (700 2425);
FORCEPROP 1 LAST TOLERANCE 5%
J 2
(425 2475);
DISPLAY 0.510638 (425 2475);
FORCEPROP 1 LAST VALUE 0
J 0
(450 2475);
DISPLAY 0.510638 (450 2475);
FORCEPROP 1 LAST MATERIAL CHIP
J 2
(350 2475);
DISPLAY 0.510638 (350 2475);
FORCEPROP 1 LAST $LOCATION R3527
J 2
(825 2475);
DISPLAY 0.510638 (825 2475);
FORCEPROP 1 LAST WATTAGE 1/16W
J 0
(425 2375);
DISPLAY 0.510638 (425 2375);
DISPLAY INVISIBLE (425 2375);
FORCEPROP 1 LAST PACK_TYPE 0402LF
J 2
(700 2375);
DISPLAY 0.510638 (700 2375);
DISPLAY INVISIBLE (700 2375);
FORCEPROP 2 LAST CDS_LIB pure_quanta
J 2
(600 2475);
DISPLAY INVISIBLE (600 2475);
FORCEPROP 1 LAST PATH I37
J 2
(650 2625);
DISPLAY 0.978723 (650 2625);
PAINT WHITE (650 2625);
DISPLAY INVISIBLE (650 2625);
FORCEPROP 0 LAST CDS_LOCATION R3527
J 2
(825 2525);
DISPLAY INVISIBLE (825 2525);
FORCEPROP 0 LAST $SEC 1
J 2
(825 2525);
DISPLAY INVISIBLE (825 2525);
FORCEPROP 0 LAST CDS_SEC 1
J 2
(825 2525);
DISPLAY INVISIBLE (825 2525);
FORCEPROP 1 LASTPIN (700 2475) $PN 1
J 2
(688 2487);
DISPLAY 0.787234 (688 2487);
PAINT MONO (688 2487);
DISPLAY INVISIBLE (688 2487);
FORCEPROP 1 LASTPIN (500 2475) $PN 2
J 2
(538 2487);
DISPLAY 0.787234 (538 2487);
PAINT MONO (538 2487);
DISPLAY INVISIBLE (538 2487);
FORCEADD Q_RES..1
R 2
(600 2625);
FORCEPROP 1 LAST PART_NUMBER CS00002JB13
J 2
(675 2575);
DISPLAY 0.319149 (675 2575);
DISPLAY INVISIBLE (675 2575);
FORCEPROP 1 LAST TOLERANCE 5%
J 2
(425 2625);
DISPLAY 0.510638 (425 2625);
FORCEPROP 1 LAST MATERIAL CHIP
J 2
(350 2625);
DISPLAY 0.510638 (350 2625);
FORCEPROP 1 LAST VALUE 0
J 0
(450 2625);
DISPLAY 0.510638 (450 2625);
FORCEPROP 1 LAST $LOCATION R3393
J 2
(825 2625);
DISPLAY 0.510638 (825 2625);
FORCEPROP 1 LASTPIN (700 2625) $PN 1
J 2
(688 2637);
DISPLAY 0.787234 (688 2637);
PAINT MONO (688 2637);
FORCEPROP 1 LASTPIN (500 2625) $PN 2
J 2
(538 2637);
DISPLAY 0.787234 (538 2637);
PAINT MONO (538 2637);
FORCEPROP 2 LAST CDS_LIB pure_quanta
J 2
(600 2625);
DISPLAY INVISIBLE (600 2625);
FORCEPROP 1 LAST WATTAGE 1/16W
J 0
(500 2550);
DISPLAY 0.319149 (500 2550);
DISPLAY INVISIBLE (500 2550);
FORCEPROP 2 LAST SEC_TYPE 0402LF
J 2
(650 2825);
DISPLAY 1.021277 (650 2825);
DISPLAY INVISIBLE (650 2825);
FORCEPROP 1 LAST PACK_TYPE 0402LF
J 2
(350 2625);
DISPLAY 0.510638 (350 2625);
DISPLAY INVISIBLE (350 2625);
FORCEPROP 1 LAST PATH I38
J 2
(650 2775);
DISPLAY 0.978723 (650 2775);
PAINT WHITE (650 2775);
DISPLAY INVISIBLE (650 2775);
FORCEPROP 0 LAST CDS_LOCATION R3393
J 2
(825 2675);
DISPLAY INVISIBLE (825 2675);
FORCEPROP 0 LAST SEC 1
J 2
(825 2675);
DISPLAY INVISIBLE (825 2675);
FORCEADD Q_RES..1
R 2
(600 2575);
FORCEPROP 1 LAST PART_NUMBER CS00002JB13
J 2
(700 2525);
DISPLAY 0.510638 (700 2525);
DISPLAY INVISIBLE (700 2525);
FORCEPROP 1 LAST MATERIAL CHIP
J 2
(350 2575);
DISPLAY 0.510638 (350 2575);
FORCEPROP 1 LAST VALUE 0
J 0
(450 2575);
DISPLAY 0.510638 (450 2575);
FORCEPROP 1 LAST TOLERANCE 5%
J 2
(425 2575);
DISPLAY 0.510638 (425 2575);
FORCEPROP 1 LAST $LOCATION R2968
J 2
(825 2575);
DISPLAY 0.510638 (825 2575);
FORCEPROP 2 LAST CDS_LIB pure_quanta
J 2
(600 2575);
DISPLAY INVISIBLE (600 2575);
FORCEPROP 1 LAST PACK_TYPE 0402LF
J 2
(700 2475);
DISPLAY 0.510638 (700 2475);
DISPLAY INVISIBLE (700 2475);
FORCEPROP 1 LAST WATTAGE 1/16W
J 0
(425 2475);
DISPLAY 0.510638 (425 2475);
DISPLAY INVISIBLE (425 2475);
FORCEPROP 1 LAST PATH I39
J 2
(650 2725);
DISPLAY 0.978723 (650 2725);
PAINT WHITE (650 2725);
DISPLAY INVISIBLE (650 2725);
FORCEPROP 0 LAST CDS_LOCATION R2968
J 2
(825 2625);
DISPLAY INVISIBLE (825 2625);
FORCEPROP 0 LAST $SEC 1
J 2
(825 2625);
DISPLAY INVISIBLE (825 2625);
FORCEPROP 0 LAST CDS_SEC 1
J 2
(825 2625);
DISPLAY INVISIBLE (825 2625);
FORCEPROP 1 LASTPIN (700 2575) $PN 1
J 2
(688 2587);
DISPLAY 0.787234 (688 2587);
PAINT MONO (688 2587);
DISPLAY INVISIBLE (688 2587);
FORCEPROP 1 LASTPIN (500 2575) $PN 2
J 2
(538 2587);
DISPLAY 0.787234 (538 2587);
PAINT MONO (538 2587);
DISPLAY INVISIBLE (538 2587);
FORCEADD UNIVERSAL_POWER..1
(-1250 1050);
FORCEPROP 3 LASTPIN (-1250 1000) SIG_NAME P3V3_AUX\g
J 0
(-1240 1010);
DISPLAY 0.659574 (-1240 1010);
PAINT MONO (-1240 1010);
DISPLAY INVISIBLE (-1240 1010);
FORCEPROP 1 LAST HDL_POWER P3V3_AUX
J 1
(-1250 1100);
DISPLAY 0.872340 (-1250 1100);
PAINT GREEN (-1250 1100);
FORCEPROP 2 LAST CDS_LIB logical_power
J 0
(-1250 1050);
PAINT MONO (-1250 1050);
DISPLAY INVISIBLE (-1250 1050);
FORCEPROP 1 LAST PATH I4
J 0
(-1200 1075);
DISPLAY 0.872340 (-1200 1075);
PAINT AQUA (-1200 1075);
DISPLAY INVISIBLE (-1200 1075);
FORCEADD Q_RES..1
R 2
(600 2675);
FORCEPROP 1 LAST PART_NUMBER CS00002JB13
J 2
(675 2800);
DISPLAY 0.319149 (675 2800);
DISPLAY INVISIBLE (675 2800);
FORCEPROP 1 LAST VALUE 0
J 0
(450 2675);
DISPLAY 0.510638 (450 2675);
FORCEPROP 1 LAST TOLERANCE 5%
J 2
(425 2675);
DISPLAY 0.510638 (425 2675);
FORCEPROP 1 LAST MATERIAL CHIP
J 2
(350 2675);
DISPLAY 0.510638 (350 2675);
FORCEPROP 1 LAST $LOCATION R3394
J 2
(825 2675);
DISPLAY 0.510638 (825 2675);
FORCEPROP 1 LAST WATTAGE 1/16W
J 0
(500 2825);
DISPLAY 0.319149 (500 2825);
DISPLAY INVISIBLE (500 2825);
FORCEPROP 1 LAST PACK_TYPE 0402LF
J 2
(350 2675);
DISPLAY 0.510638 (350 2675);
DISPLAY INVISIBLE (350 2675);
FORCEPROP 2 LAST CDS_LIB pure_quanta
J 2
(600 2675);
DISPLAY INVISIBLE (600 2675);
FORCEPROP 1 LAST PATH I40
J 2
(650 2825);
DISPLAY 0.978723 (650 2825);
PAINT WHITE (650 2825);
DISPLAY INVISIBLE (650 2825);
FORCEPROP 0 LAST CDS_LOCATION R3394
J 2
(825 2725);
DISPLAY INVISIBLE (825 2725);
FORCEPROP 0 LAST $SEC 1
J 2
(825 2725);
DISPLAY INVISIBLE (825 2725);
FORCEPROP 0 LAST CDS_SEC 1
J 2
(825 2725);
DISPLAY INVISIBLE (825 2725);
FORCEPROP 1 LASTPIN (700 2675) $PN 1
J 2
(688 2687);
DISPLAY 0.787234 (688 2687);
PAINT MONO (688 2687);
DISPLAY INVISIBLE (688 2687);
FORCEPROP 1 LASTPIN (500 2675) $PN 2
J 2
(538 2687);
DISPLAY 0.787234 (538 2687);
PAINT MONO (538 2687);
DISPLAY INVISIBLE (538 2687);
FORCEADD Q_RES..1
(500 2875);
FORCEPROP 1 LAST PART_NUMBER CS00002JB13
J 0
(425 2825);
DISPLAY 0.319149 (425 2825);
DISPLAY INVISIBLE (425 2825);
FORCEPROP 1 LAST TOLERANCE 5%
J 0
(675 2875);
DISPLAY 0.510638 (675 2875);
FORCEPROP 1 LAST VALUE 0
J 2
(650 2875);
DISPLAY 0.510638 (650 2875);
FORCEPROP 1 LAST MATERIAL CHIP
J 0
(750 2875);
DISPLAY 0.510638 (750 2875);
FORCEPROP 1 LAST $LOCATION R2268
J 0
(275 2875);
DISPLAY 0.638298 (275 2875);
FORCEPROP 1 LASTPIN (400 2875) $PN 1
J 0
(412 2887);
DISPLAY 0.787234 (412 2887);
PAINT MONO (412 2887);
FORCEPROP 1 LASTPIN (600 2875) $PN 2
J 0
(562 2887);
DISPLAY 0.787234 (562 2887);
PAINT MONO (562 2887);
FORCEPROP 2 LAST CDS_LIB pure_quanta
J 0
(500 2875);
DISPLAY INVISIBLE (500 2875);
FORCEPROP 1 LAST WATTAGE 1/16W
J 2
(600 2800);
DISPLAY 0.319149 (600 2800);
DISPLAY INVISIBLE (600 2800);
FORCEPROP 1 LAST PACK_TYPE 0402LF
J 0
(750 2875);
DISPLAY 0.510638 (750 2875);
DISPLAY INVISIBLE (750 2875);
FORCEPROP 1 LAST PATH I41
J 0
(450 3025);
DISPLAY 0.978723 (450 3025);
PAINT WHITE (450 3025);
DISPLAY INVISIBLE (450 3025);
FORCEPROP 0 LAST CDS_LOCATION R2268
J 0
(275 2925);
DISPLAY 1.021277 (275 2925);
DISPLAY INVISIBLE (275 2925);
FORCEPROP 0 LAST $SEC 1
J 0
(275 2925);
DISPLAY 0.680851 (275 2925);
PAINT MONO (275 2925);
DISPLAY INVISIBLE (275 2925);
FORCEPROP 0 LAST CDS_SEC 1
J 0
(275 2925);
DISPLAY 1.021277 (275 2925);
DISPLAY INVISIBLE (275 2925);
FORCEADD OFFPAGE..4
R 2
(1000 2975);
FORCEPROP 2 LAST $XR0 231 
J 0
(748 2975);
DISPLAY 0.638298 (748 2975);
PAINT MONO (748 2975);
FORCEPROP 1 LAST COMMENT_BODY TRUE
J 2
(1025 2875);
DISPLAY 0.872340 (1025 2875);
PAINT GREEN (1025 2875);
DISPLAY INVISIBLE (1025 2875);
FORCEPROP 1 LAST OFFPAGE TRUE
J 2
(675 2850);
DISPLAY 0.872340 (675 2850);
DISPLAY INVISIBLE (675 2850);
FORCEPROP 2 LAST CDS_LIB standard
J 2
(1000 2975);
DISPLAY INVISIBLE (1000 2975);
FORCEPROP 2 LAST PATH I42
J 0
(750 3025);
DISPLAY 1.021277 (750 3025);
DISPLAY INVISIBLE (750 3025);
FORCEADD OFFPAGE..1
(1000 3025);
FORCEPROP 2 LAST $XR0 231 
J 0
(748 3025);
DISPLAY 0.638298 (748 3025);
PAINT MONO (748 3025);
FORCEPROP 1 LAST COMMENT_BODY TRUE
J 0
(1125 2925);
DISPLAY 0.872340 (1125 2925);
PAINT GREEN (1125 2925);
DISPLAY INVISIBLE (1125 2925);
FORCEPROP 1 LAST OFFPAGE TRUE
J 0
(1325 2900);
DISPLAY 0.872340 (1325 2900);
PAINT GREEN (1325 2900);
DISPLAY INVISIBLE (1325 2900);
FORCEPROP 2 LAST CDS_LIB standard
J 0
(1000 3025);
DISPLAY INVISIBLE (1000 3025);
FORCEPROP 2 LAST PATH I43
J 0
(750 3075);
DISPLAY 1.021277 (750 3075);
DISPLAY INVISIBLE (750 3075);
FORCEADD OFFPAGE..1
(1000 3075);
FORCEPROP 2 LAST $XR0 231 
J 0
(748 3075);
DISPLAY 0.638298 (748 3075);
PAINT MONO (748 3075);
FORCEPROP 1 LAST COMMENT_BODY TRUE
J 0
(1125 2975);
DISPLAY 0.872340 (1125 2975);
PAINT GREEN (1125 2975);
DISPLAY INVISIBLE (1125 2975);
FORCEPROP 1 LAST OFFPAGE TRUE
J 0
(1325 2950);
DISPLAY 0.872340 (1325 2950);
PAINT GREEN (1325 2950);
DISPLAY INVISIBLE (1325 2950);
FORCEPROP 2 LAST CDS_LIB standard
J 0
(1000 3075);
DISPLAY INVISIBLE (1000 3075);
FORCEPROP 2 LAST PATH I44
J 0
(750 3125);
DISPLAY 1.021277 (750 3125);
DISPLAY INVISIBLE (750 3125);
FORCEADD TCA9548APWR..1
(2075 2750);
FORCEPROP 1 LAST PART_NUMBER AL009548K02
J 0
(1875 3277);
DISPLAY 0.723404 (1875 3277);
PAINT GREEN (1875 3277);
DISPLAY INVISIBLE (1875 3277);
FORCEPROP 2 LAST PART_TYPE SMLF
J 0
(1875 3425);
DISPLAY 1.021277 (1875 3425);
FORCEPROP 1 LAST MATERIAL IC
J 0
(1875 3230);
DISPLAY 0.723404 (1875 3230);
PAINT GREEN (1875 3230);
FORCEPROP 2 LAST VALUE TCA9548APWR
J 0
(1875 3375);
DISPLAY 1.021277 (1875 3375);
FORCEPROP 1 LAST LOCATION U36
J 0
(1875 3330);
DISPLAY 0.723404 (1875 3330);
PAINT GREEN (1875 3330);
FORCEPROP 2 LASTPIN (1725 3075) $PN 1
J 2
(1715 3085);
DISPLAY 0.680851 (1715 3085);
PAINT MONO (1715 3085);
FORCEPROP 2 LASTPIN (1725 3025) $PN 2
J 2
(1715 3035);
DISPLAY 0.680851 (1715 3035);
PAINT MONO (1715 3035);
FORCEPROP 2 LASTPIN (1725 2975) $PN 21
J 2
(1715 2985);
DISPLAY 0.680851 (1715 2985);
PAINT MONO (1715 2985);
FORCEPROP 2 LASTPIN (2425 2325) $PN 12
J 0
(2435 2335);
DISPLAY 0.680851 (2435 2335);
PAINT MONO (2435 2335);
FORCEPROP 2 LASTPIN (1725 2875) $PN 3
J 2
(1715 2885);
DISPLAY 0.680851 (1715 2885);
PAINT MONO (1715 2885);
FORCEPROP 2 LASTPIN (1725 2725) $PN 5
J 2
(1715 2735);
DISPLAY 0.680851 (1715 2735);
PAINT MONO (1715 2735);
FORCEPROP 2 LASTPIN (1725 2625) $PN 7
J 2
(1715 2635);
DISPLAY 0.680851 (1715 2635);
PAINT MONO (1715 2635);
FORCEPROP 2 LASTPIN (1725 2525) $PN 9
J 2
(1715 2535);
DISPLAY 0.680851 (1715 2535);
PAINT MONO (1715 2535);
FORCEPROP 2 LASTPIN (1725 2425) $PN 11
J 2
(1715 2435);
DISPLAY 0.680851 (1715 2435);
PAINT MONO (1715 2435);
FORCEPROP 2 LASTPIN (2425 2725) $PN 14
J 0
(2435 2735);
DISPLAY 0.680851 (2435 2735);
PAINT MONO (2435 2735);
FORCEPROP 2 LASTPIN (2425 2625) $PN 16
J 0
(2435 2635);
DISPLAY 0.680851 (2435 2635);
PAINT MONO (2435 2635);
FORCEPROP 2 LASTPIN (2425 2525) $PN 18
J 0
(2435 2535);
DISPLAY 0.680851 (2435 2535);
PAINT MONO (2435 2535);
FORCEPROP 2 LASTPIN (2425 2425) $PN 20
J 0
(2435 2435);
DISPLAY 0.680851 (2435 2435);
PAINT MONO (2435 2435);
FORCEPROP 2 LASTPIN (2425 2975) $PN 22
J 0
(2435 2985);
DISPLAY 0.680851 (2435 2985);
PAINT MONO (2435 2985);
FORCEPROP 2 LASTPIN (1725 2775) $PN 4
J 2
(1715 2785);
DISPLAY 0.680851 (1715 2785);
PAINT MONO (1715 2785);
FORCEPROP 2 LASTPIN (1725 2675) $PN 6
J 2
(1715 2685);
DISPLAY 0.680851 (1715 2685);
PAINT MONO (1715 2685);
FORCEPROP 2 LASTPIN (1725 2575) $PN 8
J 2
(1715 2585);
DISPLAY 0.680851 (1715 2585);
PAINT MONO (1715 2585);
FORCEPROP 2 LASTPIN (1725 2475) $PN 10
J 2
(1715 2485);
DISPLAY 0.680851 (1715 2485);
PAINT MONO (1715 2485);
FORCEPROP 2 LASTPIN (2425 2775) $PN 13
J 0
(2435 2785);
DISPLAY 0.680851 (2435 2785);
PAINT MONO (2435 2785);
FORCEPROP 2 LASTPIN (2425 2675) $PN 15
J 0
(2435 2685);
DISPLAY 0.680851 (2435 2685);
PAINT MONO (2435 2685);
FORCEPROP 2 LASTPIN (2425 2575) $PN 17
J 0
(2435 2585);
DISPLAY 0.680851 (2435 2585);
PAINT MONO (2435 2585);
FORCEPROP 2 LASTPIN (2425 2475) $PN 19
J 0
(2435 2485);
DISPLAY 0.680851 (2435 2485);
PAINT MONO (2435 2485);
FORCEPROP 2 LASTPIN (2425 3025) $PN 23
J 0
(2435 3035);
DISPLAY 0.680851 (2435 3035);
PAINT MONO (2435 3035);
FORCEPROP 2 LASTPIN (1725 3175) $PN 24
J 2
(1715 3185);
DISPLAY 0.680851 (1715 3185);
PAINT MONO (1715 3185);
FORCEPROP 2 LAST CDS_LIB pure_quanta
J 0
(2075 2750);
DISPLAY INVISIBLE (2075 2750);
FORCEPROP 1 LAST CDS_LMAN_SYM_OUTLINE -200,475,200,-475
J 0
(2075 2750);
DISPLAY 0.468085 (2075 2750);
PAINT GREEN (2075 2750);
DISPLAY INVISIBLE (2075 2750);
FORCEPROP 2 LAST SEC_TYPE 
J 0
(1875 3475);
DISPLAY 1.021277 (1875 3475);
DISPLAY INVISIBLE (1875 3475);
FORCEPROP 1 LAST NEEDS_NO_SIZE TRUE
J 0
(2075 2750);
DISPLAY 0.723404 (2075 2750);
PAINT GREEN (2075 2750);
DISPLAY INVISIBLE (2075 2750);
FORCEPROP 1 LAST PATH I45
J 0
(2075 2750);
DISPLAY 0.723404 (2075 2750);
PAINT GREEN (2075 2750);
DISPLAY INVISIBLE (2075 2750);
FORCEPROP 2 LAST SEC 1
J 0
(1875 3475);
DISPLAY 0.680851 (1875 3475);
PAINT MONO (1875 3475);
DISPLAY INVISIBLE (1875 3475);
FORCEADD UNIVERSAL_GND..1
(1200 3275);
FORCEPROP 3 LASTPIN (1200 3325) SIG_NAME GND\g
J 0
(1210 3335);
DISPLAY 0.659574 (1210 3335);
PAINT MONO (1210 3335);
DISPLAY INVISIBLE (1210 3335);
FORCEPROP 1 LAST HDL_POWER GND
J 1
(1225 3200);
DISPLAY 0.872340 (1225 3200);
PAINT GREEN (1225 3200);
DISPLAY INVISIBLE (1225 3200);
FORCEPROP 2 LAST CDS_LIB logical_power
J 0
(1200 3275);
PAINT MONO (1200 3275);
DISPLAY INVISIBLE (1200 3275);
FORCEPROP 1 LAST PATH I46
J 0
(1275 3275);
DISPLAY 0.872340 (1275 3275);
PAINT AQUA (1275 3275);
DISPLAY INVISIBLE (1275 3275);
FORCEADD Q_CAP..1
(1200 3500);
FORCEPROP 1 LAST PART_NUMBER CH4104K1B00
J 0
(1250 3350);
DISPLAY 0.510638 (1250 3350);
DISPLAY INVISIBLE (1250 3350);
FORCEPROP 1 LAST PACK_TYPE 0402
J 0
(1250 3300);
DISPLAY 0.510638 (1250 3300);
FORCEPROP 1 LAST VOLTAGE 25V
J 0
(1250 3500);
DISPLAY 0.510638 (1250 3500);
FORCEPROP 1 LAST MATERIAL X7R
J 0
(1250 3400);
DISPLAY 0.510638 (1250 3400);
FORCEPROP 1 LAST TOLERANCE 10%
J 0
(1250 3450);
DISPLAY 0.510638 (1250 3450);
FORCEPROP 1 LAST VALUE 0.1UF
J 0
(1250 3550);
DISPLAY 0.510638 (1250 3550);
FORCEPROP 1 LAST $LOCATION C174
J 0
(1250 3600);
DISPLAY 0.978723 (1250 3600);
FORCEPROP 1 LASTPIN (1200 3600) $PN 1
J 0
(1210 3580);
DISPLAY 0.787234 (1210 3580);
FORCEPROP 1 LASTPIN (1200 3400) $PN 2
J 0
(1210 3380);
DISPLAY 0.787234 (1210 3380);
FORCEPROP 2 LAST CDS_LIB pure_quanta
J 2
(1200 3500);
PAINT MONO (1200 3500);
DISPLAY INVISIBLE (1200 3500);
FORCEPROP 1 LAST PATH I47
J 0
(1250 3650);
DISPLAY 0.978723 (1250 3650);
PAINT WHITE (1250 3650);
DISPLAY INVISIBLE (1250 3650);
FORCEPROP 1 LAST $LOCATION C174
J 0
(1250 3700);
DISPLAY 1.021277 (1250 3700);
DISPLAY INVISIBLE (1250 3700);
FORCEPROP 2 LAST CDS_LOCATION C174
J 2
(1250 3700);
DISPLAY 1.021277 (1250 3700);
DISPLAY INVISIBLE (1250 3700);
FORCEPROP 2 LAST $SEC 1
J 0
(1250 3700);
DISPLAY 0.680851 (1250 3700);
PAINT MONO (1250 3700);
DISPLAY INVISIBLE (1250 3700);
FORCEPROP 2 LAST CDS_SEC 1
J 0
(1250 3700);
DISPLAY 1.021277 (1250 3700);
DISPLAY INVISIBLE (1250 3700);
FORCEADD UNIVERSAL_POWER..1
(1200 3825);
FORCEPROP 3 LASTPIN (1200 3775) SIG_NAME P3V3_AUX\g
J 0
(1210 3785);
DISPLAY 0.659574 (1210 3785);
PAINT MONO (1210 3785);
DISPLAY INVISIBLE (1210 3785);
FORCEPROP 1 LAST HDL_POWER P3V3_AUX
J 1
(1200 3875);
DISPLAY 0.872340 (1200 3875);
PAINT GREEN (1200 3875);
FORCEPROP 2 LAST CDS_LIB logical_power
J 0
(1200 3825);
PAINT MONO (1200 3825);
DISPLAY INVISIBLE (1200 3825);
FORCEPROP 1 LAST PATH I48
J 0
(1250 3850);
DISPLAY 0.872340 (1250 3850);
PAINT AQUA (1250 3850);
DISPLAY INVISIBLE (1250 3850);
FORCEADD Q_RES..1
(3875 75);
FORCEPROP 1 LAST PART_NUMBER CS22202JB07
J 0
(3725 150);
DISPLAY 0.510638 (3725 150);
DISPLAY INVISIBLE (3725 150);
FORCEPROP 1 LAST MATERIAL CHIP
J 0
(4175 75);
DISPLAY 0.510638 (4175 75);
FORCEPROP 1 LAST TOLERANCE 5%
J 0
(4100 75);
DISPLAY 0.510638 (4100 75);
FORCEPROP 1 LAST PACK_TYPE 0402LF
J 0
(3725 200);
DISPLAY 0.510638 (3725 200);
FORCEPROP 1 LAST VALUE 2.2K
J 2
(4100 75);
DISPLAY 0.510638 (4100 75);
FORCEPROP 1 LAST WATTAGE 1/16W
J 2
(4025 200);
DISPLAY 0.510638 (4025 200);
FORCEPROP 1 LAST $LOCATION R3535
J 0
(3625 75);
DISPLAY 0.510638 (3625 75);
FORCEPROP 1 LASTPIN (3775 75) $PN 1
J 0
(3787 87);
DISPLAY 0.787234 (3787 87);
FORCEPROP 1 LASTPIN (3975 75) $PN 2
J 0
(3937 87);
DISPLAY 0.787234 (3937 87);
FORCEPROP 2 LAST CDS_LIB pure_quanta
J 0
(3875 75);
PAINT MONO (3875 75);
DISPLAY INVISIBLE (3875 75);
FORCEPROP 1 LAST PATH I49
J 0
(3825 225);
DISPLAY 0.978723 (3825 225);
PAINT WHITE (3825 225);
DISPLAY INVISIBLE (3825 225);
FORCEPROP 2 LAST CDS_LOCATION R3535
J 0
(3825 275);
DISPLAY 1.021277 (3825 275);
DISPLAY INVISIBLE (3825 275);
FORCEPROP 2 LAST $SEC 1
J 0
(3825 275);
DISPLAY 0.680851 (3825 275);
PAINT MONO (3825 275);
DISPLAY INVISIBLE (3825 275);
FORCEPROP 2 LAST CDS_SEC 1
J 0
(3825 275);
DISPLAY 1.021277 (3825 275);
DISPLAY INVISIBLE (3825 275);
FORCEADD UNIVERSAL_GND..1
(-975 -200);
FORCEPROP 3 LASTPIN (-975 -150) SIG_NAME GND\g
J 0
(-965 -140);
DISPLAY 0.659574 (-965 -140);
PAINT MONO (-965 -140);
DISPLAY INVISIBLE (-965 -140);
FORCEPROP 1 LAST HDL_POWER GND
J 1
(-950 -275);
DISPLAY 0.872340 (-950 -275);
PAINT GREEN (-950 -275);
DISPLAY INVISIBLE (-950 -275);
FORCEPROP 2 LAST ROOM IO_SLOT
J 1
(-1200 -125);
DISPLAY 0.744681 (-1200 -125);
DISPLAY INVISIBLE (-1200 -125);
FORCEPROP 2 LAST CDS_LIB logical_power
J 0
(-975 -200);
PAINT MONO (-975 -200);
DISPLAY INVISIBLE (-975 -200);
FORCEPROP 1 LAST PATH I5
J 0
(-900 -200);
DISPLAY 0.872340 (-900 -200);
PAINT AQUA (-900 -200);
DISPLAY INVISIBLE (-900 -200);
FORCEADD Q_RES..1
(3875 25);
FORCEPROP 1 LAST PART_NUMBER CS22202JB07
J 0
(3775 75);
DISPLAY 0.510638 (3775 75);
DISPLAY INVISIBLE (3775 75);
FORCEPROP 1 LAST MATERIAL CHIP
J 0
(4175 25);
DISPLAY 0.510638 (4175 25);
FORCEPROP 1 LAST TOLERANCE 5%
J 0
(4100 25);
DISPLAY 0.510638 (4100 25);
FORCEPROP 1 LAST VALUE 2.2K
J 2
(4100 25);
DISPLAY 0.510638 (4100 25);
FORCEPROP 1 LAST $LOCATION R3536
J 0
(3625 25);
DISPLAY 0.510638 (3625 25);
FORCEPROP 1 LASTPIN (3775 25) $PN 1
J 0
(3787 37);
DISPLAY 0.787234 (3787 37);
FORCEPROP 1 LASTPIN (3975 25) $PN 2
J 0
(3937 37);
DISPLAY 0.787234 (3937 37);
FORCEPROP 2 LAST CDS_LIB pure_quanta
J 0
(3875 25);
PAINT MONO (3875 25);
DISPLAY INVISIBLE (3875 25);
FORCEPROP 1 LAST PACK_TYPE 0402LF
J 0
(3775 125);
DISPLAY 0.510638 (3775 125);
DISPLAY INVISIBLE (3775 125);
FORCEPROP 1 LAST WATTAGE 1/16W
J 2
(4075 125);
DISPLAY 0.510638 (4075 125);
DISPLAY INVISIBLE (4075 125);
FORCEPROP 1 LAST PATH I50
J 0
(3825 175);
DISPLAY 0.978723 (3825 175);
PAINT WHITE (3825 175);
DISPLAY INVISIBLE (3825 175);
FORCEPROP 2 LAST CDS_LOCATION R3536
J 0
(3825 225);
DISPLAY 1.021277 (3825 225);
DISPLAY INVISIBLE (3825 225);
FORCEPROP 2 LAST $SEC 1
J 0
(3825 225);
DISPLAY 0.680851 (3825 225);
PAINT MONO (3825 225);
DISPLAY INVISIBLE (3825 225);
FORCEPROP 2 LAST CDS_SEC 1
J 0
(3825 225);
DISPLAY 1.021277 (3825 225);
DISPLAY INVISIBLE (3825 225);
FORCEADD Q_RES..1
(3850 325);
FORCEPROP 1 LAST PART_NUMBER CS22202JB07
J 0
(3750 375);
DISPLAY 0.510638 (3750 375);
DISPLAY INVISIBLE (3750 375);
FORCEPROP 1 LAST TOLERANCE 5%
J 0
(4125 325);
DISPLAY 0.638298 (4125 325);
FORCEPROP 1 LAST VALUE 2.2K
J 2
(4125 325);
DISPLAY 0.638298 (4125 325);
FORCEPROP 1 LAST MATERIAL CHIP
J 0
(4225 325);
DISPLAY 0.638298 (4225 325);
FORCEPROP 1 LAST $LOCATION R3583
J 0
(3600 325);
DISPLAY 0.510638 (3600 325);
FORCEPROP 2 LAST CDS_LIB pure_quanta
J 0
(3850 325);
DISPLAY INVISIBLE (3850 325);
FORCEPROP 1 LAST PACK_TYPE 0402LF
J 0
(3750 425);
DISPLAY 0.510638 (3750 425);
DISPLAY INVISIBLE (3750 425);
FORCEPROP 1 LAST WATTAGE 1/16W
J 2
(4050 425);
DISPLAY 0.510638 (4050 425);
DISPLAY INVISIBLE (4050 425);
FORCEPROP 1 LAST PATH I51
J 0
(3800 475);
DISPLAY 0.978723 (3800 475);
PAINT WHITE (3800 475);
DISPLAY INVISIBLE (3800 475);
FORCEPROP 0 LAST CDS_LOCATION R3583
J 0
(4225 375);
DISPLAY INVISIBLE (4225 375);
FORCEPROP 0 LAST $SEC 1
J 0
(4225 375);
DISPLAY INVISIBLE (4225 375);
FORCEPROP 0 LAST CDS_SEC 1
J 0
(4225 375);
DISPLAY INVISIBLE (4225 375);
FORCEPROP 1 LASTPIN (3750 325) $PN 1
J 0
(3762 337);
DISPLAY 0.787234 (3762 337);
PAINT MONO (3762 337);
DISPLAY INVISIBLE (3762 337);
FORCEPROP 1 LASTPIN (3950 325) $PN 2
J 0
(3912 337);
DISPLAY 0.787234 (3912 337);
PAINT MONO (3912 337);
DISPLAY INVISIBLE (3912 337);
FORCEADD Q_RES..1
(3850 375);
FORCEPROP 1 LAST PART_NUMBER CS22202JB07
J 0
(3700 450);
DISPLAY 0.510638 (3700 450);
DISPLAY INVISIBLE (3700 450);
FORCEPROP 1 LAST TOLERANCE 5%
J 0
(4125 375);
DISPLAY 0.638298 (4125 375);
FORCEPROP 1 LAST VALUE 2.2K
J 2
(4125 375);
DISPLAY 0.638298 (4125 375);
FORCEPROP 1 LAST WATTAGE 1/16W
J 2
(4000 500);
DISPLAY 0.510638 (4000 500);
FORCEPROP 1 LAST MATERIAL CHIP
J 0
(4225 375);
DISPLAY 0.638298 (4225 375);
FORCEPROP 1 LAST PACK_TYPE 0402LF
J 0
(3700 500);
DISPLAY 0.510638 (3700 500);
FORCEPROP 1 LAST $LOCATION R3582
J 0
(3600 375);
DISPLAY 0.510638 (3600 375);
FORCEPROP 2 LAST CDS_LIB pure_quanta
J 0
(3850 375);
DISPLAY INVISIBLE (3850 375);
FORCEPROP 1 LAST PATH I52
J 0
(3800 525);
DISPLAY 0.978723 (3800 525);
PAINT WHITE (3800 525);
DISPLAY INVISIBLE (3800 525);
FORCEPROP 0 LAST CDS_LOCATION R3582
J 0
(4000 525);
DISPLAY INVISIBLE (4000 525);
FORCEPROP 0 LAST $SEC 1
J 0
(4000 525);
DISPLAY INVISIBLE (4000 525);
FORCEPROP 0 LAST CDS_SEC 1
J 0
(4000 525);
DISPLAY INVISIBLE (4000 525);
FORCEPROP 1 LASTPIN (3750 375) $PN 1
J 0
(3762 387);
DISPLAY 0.787234 (3762 387);
PAINT MONO (3762 387);
DISPLAY INVISIBLE (3762 387);
FORCEPROP 1 LASTPIN (3950 375) $PN 2
J 0
(3912 387);
DISPLAY 0.787234 (3912 387);
PAINT MONO (3912 387);
DISPLAY INVISIBLE (3912 387);
FORCEADD Q_RES..1
(3850 600);
FORCEPROP 1 LAST PART_NUMBER CS22202JB07
J 0
(3750 650);
DISPLAY 0.510638 (3750 650);
DISPLAY INVISIBLE (3750 650);
FORCEPROP 1 LAST TOLERANCE 5%
J 0
(4125 600);
DISPLAY 0.638298 (4125 600);
FORCEPROP 1 LAST VALUE 2.2K
J 2
(4125 600);
DISPLAY 0.638298 (4125 600);
FORCEPROP 1 LAST MATERIAL CHIP
J 0
(4225 600);
DISPLAY 0.638298 (4225 600);
FORCEPROP 1 LAST $LOCATION R3396
J 0
(3600 600);
DISPLAY 0.510638 (3600 600);
FORCEPROP 1 LAST WATTAGE 1/16W
J 2
(4050 700);
DISPLAY 0.510638 (4050 700);
DISPLAY INVISIBLE (4050 700);
FORCEPROP 1 LAST PACK_TYPE 0402LF
J 0
(3750 700);
DISPLAY 0.510638 (3750 700);
DISPLAY INVISIBLE (3750 700);
FORCEPROP 2 LAST CDS_LIB pure_quanta
J 0
(3850 600);
DISPLAY INVISIBLE (3850 600);
FORCEPROP 1 LAST PATH I53
J 0
(3800 750);
DISPLAY 0.978723 (3800 750);
PAINT WHITE (3800 750);
DISPLAY INVISIBLE (3800 750);
FORCEPROP 0 LAST CDS_LOCATION R3396
J 0
(4225 650);
DISPLAY INVISIBLE (4225 650);
FORCEPROP 0 LAST $SEC 1
J 0
(4225 650);
DISPLAY INVISIBLE (4225 650);
FORCEPROP 0 LAST CDS_SEC 1
J 0
(4225 650);
DISPLAY INVISIBLE (4225 650);
FORCEPROP 1 LASTPIN (3750 600) $PN 1
J 0
(3762 612);
DISPLAY 0.787234 (3762 612);
PAINT MONO (3762 612);
DISPLAY INVISIBLE (3762 612);
FORCEPROP 1 LASTPIN (3950 600) $PN 2
J 0
(3912 612);
DISPLAY 0.787234 (3912 612);
PAINT MONO (3912 612);
DISPLAY INVISIBLE (3912 612);
FORCEADD Q_RES..1
(3850 650);
FORCEPROP 1 LAST PART_NUMBER CS22202JB07
J 0
(3700 725);
DISPLAY 0.510638 (3700 725);
DISPLAY INVISIBLE (3700 725);
FORCEPROP 1 LAST VALUE 2.2K
J 2
(4125 650);
DISPLAY 0.638298 (4125 650);
FORCEPROP 1 LAST PACK_TYPE 0402LF
J 0
(3700 775);
DISPLAY 0.510638 (3700 775);
FORCEPROP 1 LAST MATERIAL CHIP
J 0
(4225 650);
DISPLAY 0.638298 (4225 650);
FORCEPROP 1 LAST TOLERANCE 5%
J 0
(4125 650);
DISPLAY 0.638298 (4125 650);
FORCEPROP 1 LAST WATTAGE 1/16W
J 2
(4000 775);
DISPLAY 0.510638 (4000 775);
FORCEPROP 1 LAST $LOCATION R3395
J 0
(3600 650);
DISPLAY 0.510638 (3600 650);
FORCEPROP 2 LAST CDS_LIB pure_quanta
J 0
(3850 650);
DISPLAY INVISIBLE (3850 650);
FORCEPROP 1 LAST PATH I54
J 0
(3800 800);
DISPLAY 0.978723 (3800 800);
PAINT WHITE (3800 800);
DISPLAY INVISIBLE (3800 800);
FORCEPROP 0 LAST CDS_LOCATION R3395
J 0
(4000 800);
DISPLAY INVISIBLE (4000 800);
FORCEPROP 0 LAST $SEC 1
J 0
(4000 800);
DISPLAY INVISIBLE (4000 800);
FORCEPROP 0 LAST CDS_SEC 1
J 0
(4000 800);
DISPLAY INVISIBLE (4000 800);
FORCEPROP 1 LASTPIN (3750 650) $PN 1
J 0
(3762 662);
DISPLAY 0.787234 (3762 662);
PAINT MONO (3762 662);
DISPLAY INVISIBLE (3762 662);
FORCEPROP 1 LASTPIN (3950 650) $PN 2
J 0
(3912 662);
DISPLAY 0.787234 (3912 662);
PAINT MONO (3912 662);
DISPLAY INVISIBLE (3912 662);
FORCEADD UNIVERSAL_POWER..1
(3425 1225);
FORCEPROP 3 LASTPIN (3425 1175) SIG_NAME P3V3_AUX\g
J 0
(3435 1185);
DISPLAY 0.659574 (3435 1185);
PAINT MONO (3435 1185);
DISPLAY INVISIBLE (3435 1185);
FORCEPROP 1 LAST HDL_POWER P3V3_AUX
J 1
(3425 1275);
DISPLAY 0.872340 (3425 1275);
PAINT GREEN (3425 1275);
FORCEPROP 2 LAST CDS_LIB logical_power
J 0
(3425 1225);
PAINT MONO (3425 1225);
DISPLAY INVISIBLE (3425 1225);
FORCEPROP 1 LAST PATH I55
J 0
(3475 1250);
DISPLAY 0.872340 (3475 1250);
PAINT AQUA (3475 1250);
DISPLAY INVISIBLE (3475 1250);
FORCEADD Q_RES..1
(3850 975);
FORCEPROP 1 LAST PART_NUMBER CS22202JB07
J 0
(3750 1025);
DISPLAY 0.510638 (3750 1025);
DISPLAY INVISIBLE (3750 1025);
FORCEPROP 1 LAST TOLERANCE 5%
J 0
(4125 975);
DISPLAY 0.638298 (4125 975);
FORCEPROP 1 LAST VALUE 2.2K
J 2
(4125 975);
DISPLAY 0.638298 (4125 975);
FORCEPROP 1 LAST MATERIAL EMPTY
J 0
(4225 975);
DISPLAY 0.638298 (4225 975);
PAINT RED (4225 975);
FORCEPROP 1 LAST $LOCATION R2205
J 0
(3600 975);
DISPLAY 0.510638 (3600 975);
FORCEPROP 2 LAST CDS_LIB pure_quanta
J 0
(3850 975);
DISPLAY INVISIBLE (3850 975);
FORCEPROP 1 LAST PACK_TYPE 0402LF
J 0
(3750 1075);
DISPLAY 0.510638 (3750 1075);
DISPLAY INVISIBLE (3750 1075);
FORCEPROP 1 LAST WATTAGE 1/16W
J 2
(4050 1075);
DISPLAY 0.510638 (4050 1075);
DISPLAY INVISIBLE (4050 1075);
FORCEPROP 1 LAST PATH I56
J 0
(3800 1125);
DISPLAY 0.978723 (3800 1125);
PAINT WHITE (3800 1125);
DISPLAY INVISIBLE (3800 1125);
FORCEPROP 0 LAST CDS_LOCATION R2205
J 0
(4225 1025);
DISPLAY INVISIBLE (4225 1025);
FORCEPROP 0 LAST $SEC 1
J 0
(4225 1025);
DISPLAY INVISIBLE (4225 1025);
FORCEPROP 0 LAST CDS_SEC 1
J 0
(4225 1025);
DISPLAY INVISIBLE (4225 1025);
FORCEPROP 1 LASTPIN (3750 975) $PN 1
J 0
(3762 987);
DISPLAY 0.787234 (3762 987);
PAINT MONO (3762 987);
DISPLAY INVISIBLE (3762 987);
FORCEPROP 1 LASTPIN (3950 975) $PN 2
J 0
(3912 987);
DISPLAY 0.787234 (3912 987);
PAINT MONO (3912 987);
DISPLAY INVISIBLE (3912 987);
FORCEADD Q_RES..1
(3850 1025);
FORCEPROP 1 LAST PART_NUMBER CS22202JB07
J 0
(3700 1100);
DISPLAY 0.510638 (3700 1100);
DISPLAY INVISIBLE (3700 1100);
FORCEPROP 1 LAST WATTAGE 1/16W
J 2
(4000 1150);
DISPLAY 0.510638 (4000 1150);
FORCEPROP 1 LAST PACK_TYPE 0402LF
J 0
(3700 1150);
DISPLAY 0.510638 (3700 1150);
FORCEPROP 1 LAST TOLERANCE 5%
J 0
(4125 1025);
DISPLAY 0.638298 (4125 1025);
FORCEPROP 1 LAST VALUE 2.2K
J 2
(4125 1025);
DISPLAY 0.638298 (4125 1025);
FORCEPROP 1 LAST MATERIAL EMPTY
J 0
(4225 1025);
DISPLAY 0.638298 (4225 1025);
PAINT RED (4225 1025);
FORCEPROP 1 LAST $LOCATION R2204
J 0
(3600 1025);
DISPLAY 0.510638 (3600 1025);
FORCEPROP 2 LAST CDS_LIB pure_quanta
J 0
(3850 1025);
DISPLAY INVISIBLE (3850 1025);
FORCEPROP 1 LAST PATH I57
J 0
(3800 1175);
DISPLAY 0.978723 (3800 1175);
PAINT WHITE (3800 1175);
DISPLAY INVISIBLE (3800 1175);
FORCEPROP 0 LAST CDS_LOCATION R2204
J 0
(4000 1175);
DISPLAY INVISIBLE (4000 1175);
FORCEPROP 0 LAST $SEC 1
J 0
(4000 1175);
DISPLAY INVISIBLE (4000 1175);
FORCEPROP 0 LAST CDS_SEC 1
J 0
(4000 1175);
DISPLAY INVISIBLE (4000 1175);
FORCEPROP 1 LASTPIN (3750 1025) $PN 1
J 0
(3762 1037);
DISPLAY 0.787234 (3762 1037);
PAINT MONO (3762 1037);
DISPLAY INVISIBLE (3762 1037);
FORCEPROP 1 LASTPIN (3950 1025) $PN 2
J 0
(3912 1037);
DISPLAY 0.787234 (3912 1037);
PAINT MONO (3912 1037);
DISPLAY INVISIBLE (3912 1037);
FORCEADD UNIVERSAL_GND..1
(2575 2150);
FORCEPROP 3 LASTPIN (2575 2200) SIG_NAME GND\g
J 0
(2585 2210);
DISPLAY 0.659574 (2585 2210);
PAINT MONO (2585 2210);
DISPLAY INVISIBLE (2585 2210);
FORCEPROP 1 LAST HDL_POWER GND
J 1
(2600 2075);
DISPLAY 0.872340 (2600 2075);
PAINT GREEN (2600 2075);
DISPLAY INVISIBLE (2600 2075);
FORCEPROP 2 LAST CDS_LIB logical_power
J 0
(2575 2150);
DISPLAY INVISIBLE (2575 2150);
FORCEPROP 1 LAST PATH I58
J 0
(2650 2150);
DISPLAY 0.872340 (2650 2150);
PAINT AQUA (2650 2150);
DISPLAY INVISIBLE (2650 2150);
FORCEADD Q_RES..1
(3400 2525);
FORCEPROP 1 LAST PART_NUMBER CS00002JB13
J 0
(3325 2475);
DISPLAY 0.319149 (3325 2475);
DISPLAY INVISIBLE (3325 2475);
FORCEPROP 1 LAST MATERIAL CHIP
J 0
(3650 2525);
DISPLAY 0.510638 (3650 2525);
FORCEPROP 1 LAST TOLERANCE 5%
J 0
(3575 2525);
DISPLAY 0.510638 (3575 2525);
FORCEPROP 1 LAST VALUE 0
J 2
(3550 2525);
DISPLAY 0.510638 (3550 2525);
FORCEPROP 1 LAST $LOCATION R3580
J 0
(3175 2525);
DISPLAY 0.510638 (3175 2525);
FORCEPROP 2 LAST CDS_LIB pure_quanta
J 0
(3400 2525);
DISPLAY INVISIBLE (3400 2525);
FORCEPROP 1 LAST WATTAGE 1/16W
J 2
(3500 2450);
DISPLAY 0.319149 (3500 2450);
DISPLAY INVISIBLE (3500 2450);
FORCEPROP 1 LAST PACK_TYPE 0402LF
J 0
(3650 2525);
DISPLAY 0.510638 (3650 2525);
DISPLAY INVISIBLE (3650 2525);
FORCEPROP 1 LAST PATH I59
J 0
(3350 2675);
DISPLAY 0.978723 (3350 2675);
PAINT WHITE (3350 2675);
DISPLAY INVISIBLE (3350 2675);
FORCEPROP 0 LAST CDS_LOCATION R3580
J 0
(3175 2575);
DISPLAY INVISIBLE (3175 2575);
FORCEPROP 0 LAST $SEC 1
J 0
(3175 2575);
DISPLAY INVISIBLE (3175 2575);
FORCEPROP 0 LAST CDS_SEC 1
J 0
(3175 2575);
DISPLAY INVISIBLE (3175 2575);
FORCEPROP 1 LASTPIN (3300 2525) $PN 1
J 0
(3312 2537);
DISPLAY 0.787234 (3312 2537);
PAINT MONO (3312 2537);
DISPLAY INVISIBLE (3312 2537);
FORCEPROP 1 LASTPIN (3500 2525) $PN 2
J 0
(3462 2537);
DISPLAY 0.787234 (3462 2537);
PAINT MONO (3462 2537);
DISPLAY INVISIBLE (3462 2537);
FORCEADD Q_RES..2
(-975 25);
FORCEPROP 1 LAST PART_NUMBER CS21002FB06
J 0
(-935 -100);
DISPLAY 0.510638 (-935 -100);
DISPLAY INVISIBLE (-935 -100);
FORCEPROP 1 LAST TOLERANCE 1%
J 0
(-930 50);
DISPLAY 0.638298 (-930 50);
FORCEPROP 1 LAST WATTAGE 1/16W
J 0
(-935 0);
DISPLAY 0.638298 (-935 0);
FORCEPROP 1 LAST MATERIAL CHIP
J 0
(-935 -50);
DISPLAY 0.638298 (-935 -50);
FORCEPROP 1 LAST VALUE 1K
J 0
(-930 100);
DISPLAY 0.638298 (-930 100);
FORCEPROP 1 LAST PACK_TYPE 0402LF
J 0
(-935 -100);
DISPLAY 0.638298 (-935 -100);
FORCEPROP 1 LAST $LOCATION R539
J 0
(-930 150);
DISPLAY 0.978723 (-930 150);
FORCEPROP 1 LASTPIN (-975 125) $PN 1
J 0
(-970 87);
DISPLAY 0.787234 (-970 87);
FORCEPROP 1 LASTPIN (-975 -75) $PN 2
J 0
(-970 -65);
DISPLAY 0.787234 (-970 -65);
FORCEPROP 2 LAST CDS_LIB pure_quanta
J 0
(-975 25);
PAINT MONO (-975 25);
DISPLAY INVISIBLE (-975 25);
FORCEPROP 1 LAST PATH I6
J 0
(-925 200);
DISPLAY 0.978723 (-925 200);
PAINT WHITE (-925 200);
DISPLAY INVISIBLE (-925 200);
FORCEPROP 1 LAST $LOCATION R539
J 0
(-925 250);
DISPLAY 1.021277 (-925 250);
DISPLAY INVISIBLE (-925 250);
FORCEPROP 2 LAST CDS_LOCATION R539
J 0
(-925 250);
DISPLAY 1.021277 (-925 250);
DISPLAY INVISIBLE (-925 250);
FORCEPROP 2 LAST $SEC 1
J 0
(-925 250);
DISPLAY 0.680851 (-925 250);
PAINT MONO (-925 250);
DISPLAY INVISIBLE (-925 250);
FORCEPROP 2 LAST CDS_SEC 1
J 0
(-925 250);
DISPLAY 1.021277 (-925 250);
DISPLAY INVISIBLE (-925 250);
FORCEADD Q_RES..1
(3400 2575);
FORCEPROP 1 LAST PART_NUMBER CS00002JB13
J 0
(3325 2700);
DISPLAY 0.319149 (3325 2700);
DISPLAY INVISIBLE (3325 2700);
FORCEPROP 1 LAST MATERIAL CHIP
J 0
(3650 2575);
DISPLAY 0.510638 (3650 2575);
FORCEPROP 1 LAST VALUE 0
J 2
(3550 2575);
DISPLAY 0.510638 (3550 2575);
FORCEPROP 1 LAST TOLERANCE 5%
J 0
(3575 2575);
DISPLAY 0.510638 (3575 2575);
FORCEPROP 1 LAST $LOCATION R3581
J 0
(3175 2575);
DISPLAY 0.510638 (3175 2575);
FORCEPROP 1 LAST WATTAGE 1/16W
J 2
(3500 2725);
DISPLAY 0.319149 (3500 2725);
DISPLAY INVISIBLE (3500 2725);
FORCEPROP 1 LAST PACK_TYPE 0402LF
J 0
(3650 2575);
DISPLAY 0.510638 (3650 2575);
DISPLAY INVISIBLE (3650 2575);
FORCEPROP 2 LAST CDS_LIB pure_quanta
J 0
(3400 2575);
DISPLAY INVISIBLE (3400 2575);
FORCEPROP 1 LAST PATH I60
J 0
(3350 2725);
DISPLAY 0.978723 (3350 2725);
PAINT WHITE (3350 2725);
DISPLAY INVISIBLE (3350 2725);
FORCEPROP 0 LAST CDS_LOCATION R3581
J 0
(3175 2625);
DISPLAY INVISIBLE (3175 2625);
FORCEPROP 0 LAST $SEC 1
J 0
(3175 2625);
DISPLAY INVISIBLE (3175 2625);
FORCEPROP 0 LAST CDS_SEC 1
J 0
(3175 2625);
DISPLAY INVISIBLE (3175 2625);
FORCEPROP 1 LASTPIN (3300 2575) $PN 1
J 0
(3312 2587);
DISPLAY 0.787234 (3312 2587);
PAINT MONO (3312 2587);
DISPLAY INVISIBLE (3312 2587);
FORCEPROP 1 LASTPIN (3500 2575) $PN 2
J 0
(3462 2587);
DISPLAY 0.787234 (3462 2587);
PAINT MONO (3462 2587);
DISPLAY INVISIBLE (3462 2587);
FORCEADD Q_RES..1
(3400 2625);
FORCEPROP 1 LAST PART_NUMBER CS00002JB13
J 0
(3325 2575);
DISPLAY 0.319149 (3325 2575);
DISPLAY INVISIBLE (3325 2575);
FORCEPROP 1 LAST VALUE 0
J 2
(3550 2625);
DISPLAY 0.510638 (3550 2625);
FORCEPROP 1 LAST MATERIAL CHIP
J 0
(3650 2625);
DISPLAY 0.510638 (3650 2625);
FORCEPROP 1 LAST TOLERANCE 5%
J 0
(3575 2625);
DISPLAY 0.510638 (3575 2625);
FORCEPROP 1 LAST $LOCATION R2565
J 0
(3175 2625);
DISPLAY 0.510638 (3175 2625);
FORCEPROP 1 LAST PACK_TYPE 0402LF
J 0
(3650 2625);
DISPLAY 0.510638 (3650 2625);
DISPLAY INVISIBLE (3650 2625);
FORCEPROP 1 LAST WATTAGE 1/16W
J 2
(3500 2550);
DISPLAY 0.319149 (3500 2550);
DISPLAY INVISIBLE (3500 2550);
FORCEPROP 2 LAST CDS_LIB pure_quanta
J 0
(3400 2625);
DISPLAY INVISIBLE (3400 2625);
FORCEPROP 1 LAST PATH I61
J 0
(3350 2775);
DISPLAY 0.978723 (3350 2775);
PAINT WHITE (3350 2775);
DISPLAY INVISIBLE (3350 2775);
FORCEPROP 0 LAST CDS_LOCATION R2565
J 0
(3175 2675);
DISPLAY INVISIBLE (3175 2675);
FORCEPROP 0 LAST $SEC 1
J 0
(3175 2675);
DISPLAY INVISIBLE (3175 2675);
FORCEPROP 0 LAST CDS_SEC 1
J 0
(3175 2675);
DISPLAY INVISIBLE (3175 2675);
FORCEPROP 1 LASTPIN (3300 2625) $PN 1
J 0
(3312 2637);
DISPLAY 0.787234 (3312 2637);
PAINT MONO (3312 2637);
DISPLAY INVISIBLE (3312 2637);
FORCEPROP 1 LASTPIN (3500 2625) $PN 2
J 0
(3462 2637);
DISPLAY 0.787234 (3462 2637);
PAINT MONO (3462 2637);
DISPLAY INVISIBLE (3462 2637);
FORCEADD Q_RES..1
(3400 2675);
FORCEPROP 1 LAST PART_NUMBER CS00002JB13
J 0
(3325 2800);
DISPLAY 0.319149 (3325 2800);
DISPLAY INVISIBLE (3325 2800);
FORCEPROP 1 LAST VALUE 0
J 2
(3550 2675);
DISPLAY 0.510638 (3550 2675);
FORCEPROP 1 LAST MATERIAL CHIP
J 0
(3650 2675);
DISPLAY 0.510638 (3650 2675);
FORCEPROP 1 LAST TOLERANCE 5%
J 0
(3575 2675);
DISPLAY 0.510638 (3575 2675);
FORCEPROP 1 LAST $LOCATION R2566
J 0
(3175 2675);
DISPLAY 0.510638 (3175 2675);
FORCEPROP 2 LAST CDS_LIB pure_quanta
J 0
(3400 2675);
DISPLAY INVISIBLE (3400 2675);
FORCEPROP 1 LAST PACK_TYPE 0402LF
J 0
(3650 2675);
DISPLAY 0.510638 (3650 2675);
DISPLAY INVISIBLE (3650 2675);
FORCEPROP 1 LAST WATTAGE 1/16W
J 2
(3500 2825);
DISPLAY 0.319149 (3500 2825);
DISPLAY INVISIBLE (3500 2825);
FORCEPROP 1 LAST PATH I62
J 0
(3350 2825);
DISPLAY 0.978723 (3350 2825);
PAINT WHITE (3350 2825);
DISPLAY INVISIBLE (3350 2825);
FORCEPROP 0 LAST CDS_LOCATION R2566
J 0
(3175 2725);
DISPLAY INVISIBLE (3175 2725);
FORCEPROP 0 LAST $SEC 1
J 0
(3175 2725);
DISPLAY INVISIBLE (3175 2725);
FORCEPROP 0 LAST CDS_SEC 1
J 0
(3175 2725);
DISPLAY INVISIBLE (3175 2725);
FORCEPROP 1 LASTPIN (3300 2675) $PN 1
J 0
(3312 2687);
DISPLAY 0.787234 (3312 2687);
PAINT MONO (3312 2687);
DISPLAY INVISIBLE (3312 2687);
FORCEPROP 1 LASTPIN (3500 2675) $PN 2
J 0
(3462 2687);
DISPLAY 0.787234 (3462 2687);
PAINT MONO (3462 2687);
DISPLAY INVISIBLE (3462 2687);
FORCEADD Q_RES..1
(3400 2725);
FORCEPROP 1 LAST PART_NUMBER CS00002JB13
J 0
(3325 2675);
DISPLAY 0.319149 (3325 2675);
DISPLAY INVISIBLE (3325 2675);
FORCEPROP 1 LAST VALUE 0
J 2
(3550 2725);
DISPLAY 0.510638 (3550 2725);
FORCEPROP 1 LAST MATERIAL CHIP
J 0
(3650 2725);
DISPLAY 0.510638 (3650 2725);
FORCEPROP 1 LAST TOLERANCE 5%
J 0
(3575 2725);
DISPLAY 0.510638 (3575 2725);
FORCEPROP 1 LAST $LOCATION R2703
J 0
(3175 2725);
DISPLAY 0.510638 (3175 2725);
FORCEPROP 1 LAST PACK_TYPE 0402LF
J 0
(3650 2725);
DISPLAY 0.510638 (3650 2725);
DISPLAY INVISIBLE (3650 2725);
FORCEPROP 1 LAST WATTAGE 1/16W
J 2
(3500 2650);
DISPLAY 0.319149 (3500 2650);
DISPLAY INVISIBLE (3500 2650);
FORCEPROP 2 LAST CDS_LIB pure_quanta
J 0
(3400 2725);
DISPLAY INVISIBLE (3400 2725);
FORCEPROP 1 LAST PATH I63
J 0
(3350 2875);
DISPLAY 0.978723 (3350 2875);
PAINT WHITE (3350 2875);
DISPLAY INVISIBLE (3350 2875);
FORCEPROP 0 LAST CDS_LOCATION R2703
J 0
(3175 2775);
DISPLAY INVISIBLE (3175 2775);
FORCEPROP 0 LAST $SEC 1
J 0
(3175 2775);
DISPLAY INVISIBLE (3175 2775);
FORCEPROP 0 LAST CDS_SEC 1
J 0
(3175 2775);
DISPLAY INVISIBLE (3175 2775);
FORCEPROP 1 LASTPIN (3300 2725) $PN 1
J 0
(3312 2737);
DISPLAY 0.787234 (3312 2737);
PAINT MONO (3312 2737);
DISPLAY INVISIBLE (3312 2737);
FORCEPROP 1 LASTPIN (3500 2725) $PN 2
J 0
(3462 2737);
DISPLAY 0.787234 (3462 2737);
PAINT MONO (3462 2737);
DISPLAY INVISIBLE (3462 2737);
FORCEADD Q_RES..1
(3400 2775);
FORCEPROP 1 LAST PART_NUMBER CS00002JB13
J 0
(3300 2725);
DISPLAY 0.510638 (3300 2725);
DISPLAY INVISIBLE (3300 2725);
FORCEPROP 1 LAST VALUE 0
J 2
(3550 2775);
DISPLAY 0.510638 (3550 2775);
FORCEPROP 1 LAST TOLERANCE 5%
J 0
(3575 2775);
DISPLAY 0.510638 (3575 2775);
FORCEPROP 1 LAST MATERIAL CHIP
J 0
(3650 2775);
DISPLAY 0.510638 (3650 2775);
FORCEPROP 1 LAST $LOCATION R2704
J 0
(3175 2775);
DISPLAY 0.510638 (3175 2775);
FORCEPROP 2 LAST CDS_LIB pure_quanta
J 0
(3400 2775);
DISPLAY INVISIBLE (3400 2775);
FORCEPROP 1 LAST PACK_TYPE 0402LF
J 0
(3300 2675);
DISPLAY 0.510638 (3300 2675);
DISPLAY INVISIBLE (3300 2675);
FORCEPROP 1 LAST WATTAGE 1/16W
J 2
(3575 2675);
DISPLAY 0.510638 (3575 2675);
DISPLAY INVISIBLE (3575 2675);
FORCEPROP 1 LAST PATH I64
J 0
(3350 2925);
DISPLAY 0.978723 (3350 2925);
PAINT WHITE (3350 2925);
DISPLAY INVISIBLE (3350 2925);
FORCEPROP 0 LAST CDS_LOCATION R2704
J 0
(3175 2825);
DISPLAY INVISIBLE (3175 2825);
FORCEPROP 0 LAST $SEC 1
J 0
(3175 2825);
DISPLAY INVISIBLE (3175 2825);
FORCEPROP 0 LAST CDS_SEC 1
J 0
(3175 2825);
DISPLAY INVISIBLE (3175 2825);
FORCEPROP 1 LASTPIN (3300 2775) $PN 1
J 0
(3312 2787);
DISPLAY 0.787234 (3312 2787);
PAINT MONO (3312 2787);
DISPLAY INVISIBLE (3312 2787);
FORCEPROP 1 LASTPIN (3500 2775) $PN 2
J 0
(3462 2787);
DISPLAY 0.787234 (3462 2787);
PAINT MONO (3462 2787);
DISPLAY INVISIBLE (3462 2787);
FORCEADD Q_RES..1
R 2
(3475 2975);
FORCEPROP 1 LAST PART_NUMBER CS03322FB03
J 2
(3575 3100);
DISPLAY 0.404255 (3575 3100);
DISPLAY INVISIBLE (3575 3100);
FORCEPROP 1 LAST VALUE 33.2
J 0
(3275 2975);
DISPLAY 0.404255 (3275 2975);
FORCEPROP 1 LAST WATTAGE 1/16W
J 0
(3350 3150);
DISPLAY 0.404255 (3350 3150);
FORCEPROP 1 LAST PACK_TYPE 0402LF
J 2
(3575 3150);
DISPLAY 0.404255 (3575 3150);
FORCEPROP 1 LAST TOLERANCE 1%
J 2
(3250 2975);
DISPLAY 0.404255 (3250 2975);
FORCEPROP 1 LAST MATERIAL CHIP
J 2
(3200 2975);
DISPLAY 0.404255 (3200 2975);
FORCEPROP 1 LAST $LOCATION R588
J 2
(3700 2975);
DISPLAY 0.510638 (3700 2975);
FORCEPROP 1 LASTPIN (3575 2975) $PN 1
J 2
(3563 2987);
DISPLAY 0.787234 (3563 2987);
FORCEPROP 1 LASTPIN (3375 2975) $PN 2
J 2
(3413 2987);
DISPLAY 0.787234 (3413 2987);
FORCEPROP 2 LAST CDS_LIB pure_quanta
J 2
(3475 2975);
PAINT MONO (3475 2975);
DISPLAY INVISIBLE (3475 2975);
FORCEPROP 1 LAST PATH I65
J 2
(3525 3125);
DISPLAY 0.978723 (3525 3125);
PAINT WHITE (3525 3125);
DISPLAY INVISIBLE (3525 3125);
FORCEPROP 1 LAST $LOCATION R588
J 2
(3525 3175);
DISPLAY 1.021277 (3525 3175);
DISPLAY INVISIBLE (3525 3175);
FORCEPROP 2 LAST CDS_LOCATION R588
J 2
(3525 3175);
DISPLAY 1.021277 (3525 3175);
DISPLAY INVISIBLE (3525 3175);
FORCEPROP 2 LAST $SEC 1
J 2
(3525 3175);
DISPLAY 0.680851 (3525 3175);
PAINT MONO (3525 3175);
DISPLAY INVISIBLE (3525 3175);
FORCEPROP 2 LAST CDS_SEC 1
J 2
(3525 3175);
DISPLAY 1.021277 (3525 3175);
DISPLAY INVISIBLE (3525 3175);
FORCEADD Q_RES..1
R 2
(3475 3025);
FORCEPROP 1 LAST PART_NUMBER CS03322FB03
J 2
(3550 2975);
DISPLAY 0.319149 (3550 2975);
DISPLAY INVISIBLE (3550 2975);
FORCEPROP 1 LAST TOLERANCE 1%
J 2
(3250 3025);
DISPLAY 0.404255 (3250 3025);
FORCEPROP 1 LAST MATERIAL CHIP
J 2
(3200 3025);
DISPLAY 0.404255 (3200 3025);
FORCEPROP 1 LAST VALUE 33.2
J 0
(3275 3025);
DISPLAY 0.404255 (3275 3025);
FORCEPROP 1 LAST $LOCATION R589
J 2
(3700 3025);
DISPLAY 0.510638 (3700 3025);
FORCEPROP 1 LASTPIN (3575 3025) $PN 1
J 2
(3563 3037);
DISPLAY 0.787234 (3563 3037);
FORCEPROP 1 LASTPIN (3375 3025) $PN 2
J 2
(3413 3037);
DISPLAY 0.787234 (3413 3037);
FORCEPROP 1 LAST WATTAGE 1/16W
J 0
(3375 2950);
DISPLAY 0.319149 (3375 2950);
DISPLAY INVISIBLE (3375 2950);
FORCEPROP 2 LAST CDS_LIB pure_quanta
J 2
(3475 3025);
PAINT MONO (3475 3025);
DISPLAY INVISIBLE (3475 3025);
FORCEPROP 1 LAST PACK_TYPE 0402LF
J 2
(3225 3025);
DISPLAY 0.404255 (3225 3025);
DISPLAY INVISIBLE (3225 3025);
FORCEPROP 1 LAST PATH I66
J 2
(3525 3175);
DISPLAY 0.978723 (3525 3175);
PAINT WHITE (3525 3175);
DISPLAY INVISIBLE (3525 3175);
FORCEPROP 1 LAST $LOCATION R589
J 2
(3525 3225);
DISPLAY 1.021277 (3525 3225);
DISPLAY INVISIBLE (3525 3225);
FORCEPROP 2 LAST CDS_LOCATION R589
J 2
(3525 3225);
DISPLAY 1.021277 (3525 3225);
DISPLAY INVISIBLE (3525 3225);
FORCEPROP 2 LAST $SEC 1
J 2
(3525 3225);
DISPLAY 0.680851 (3525 3225);
PAINT MONO (3525 3225);
DISPLAY INVISIBLE (3525 3225);
FORCEPROP 2 LAST CDS_SEC 1
J 2
(3525 3225);
DISPLAY 1.021277 (3525 3225);
DISPLAY INVISIBLE (3525 3225);
FORCEADD OFFPAGE..2
(5275 25);
FORCEPROP 2 LAST $XR0 194 
J 0
(5464 25);
DISPLAY 0.638298 (5464 25);
PAINT MONO (5464 25);
FORCEPROP 2 LAST $XR1 231 
J 0
(5584 25);
DISPLAY 0.638298 (5584 25);
PAINT MONO (5584 25);
FORCEPROP 1 LAST COMMENT_BODY TRUE
J 0
(5230 -70);
DISPLAY 0.872340 (5230 -70);
PAINT GREEN (5230 -70);
DISPLAY INVISIBLE (5230 -70);
FORCEPROP 1 LAST OFFPAGE TRUE
J 0
(5600 -100);
DISPLAY 0.872340 (5600 -100);
PAINT GREEN (5600 -100);
DISPLAY INVISIBLE (5600 -100);
FORCEPROP 2 LAST CDS_LIB standard
J 0
(5275 25);
PAINT MONO (5275 25);
DISPLAY INVISIBLE (5275 25);
FORCEPROP 2 LAST PATH I67
J 0
(5600 75);
DISPLAY 1.021277 (5600 75);
DISPLAY INVISIBLE (5600 75);
FORCEADD OFFPAGE..2
(5275 75);
FORCEPROP 2 LAST $XR0 231 
J 0
(5464 75);
DISPLAY 0.638298 (5464 75);
PAINT MONO (5464 75);
FORCEPROP 2 LAST $XR1 194 
J 0
(5584 75);
DISPLAY 0.638298 (5584 75);
PAINT MONO (5584 75);
FORCEPROP 1 LAST COMMENT_BODY TRUE
J 0
(5230 -20);
DISPLAY 0.872340 (5230 -20);
PAINT GREEN (5230 -20);
DISPLAY INVISIBLE (5230 -20);
FORCEPROP 1 LAST OFFPAGE TRUE
J 0
(5600 -50);
DISPLAY 0.872340 (5600 -50);
PAINT GREEN (5600 -50);
DISPLAY INVISIBLE (5600 -50);
FORCEPROP 2 LAST CDS_LIB standard
J 0
(5275 75);
PAINT MONO (5275 75);
DISPLAY INVISIBLE (5275 75);
FORCEPROP 2 LAST PATH I68
J 0
(5600 125);
DISPLAY 1.021277 (5600 125);
DISPLAY INVISIBLE (5600 125);
FORCEADD OFFPAGE..2
(5250 325);
FORCEPROP 2 LAST $XR0 231 
J 0
(5439 325);
DISPLAY 0.638298 (5439 325);
PAINT MONO (5439 325);
FORCEPROP 2 LAST $XR1 227 
J 0
(5559 325);
DISPLAY 0.638298 (5559 325);
PAINT MONO (5559 325);
FORCEPROP 1 LAST COMMENT_BODY TRUE
J 0
(5205 230);
DISPLAY 0.872340 (5205 230);
PAINT GREEN (5205 230);
DISPLAY INVISIBLE (5205 230);
FORCEPROP 1 LAST OFFPAGE TRUE
J 0
(5575 200);
DISPLAY 0.872340 (5575 200);
PAINT GREEN (5575 200);
DISPLAY INVISIBLE (5575 200);
FORCEPROP 2 LAST CDS_LIB standard
J 0
(5250 325);
PAINT MONO (5250 325);
DISPLAY INVISIBLE (5250 325);
FORCEPROP 2 LAST PATH I69
J 0
(5575 375);
DISPLAY 1.021277 (5575 375);
DISPLAY INVISIBLE (5575 375);
FORCEADD UNIVERSAL_GND..1
(-700 -200);
FORCEPROP 3 LASTPIN (-700 -150) SIG_NAME GND\g
J 0
(-690 -140);
DISPLAY 0.659574 (-690 -140);
PAINT MONO (-690 -140);
DISPLAY INVISIBLE (-690 -140);
FORCEPROP 1 LAST HDL_POWER GND
J 1
(-675 -275);
DISPLAY 0.872340 (-675 -275);
PAINT GREEN (-675 -275);
DISPLAY INVISIBLE (-675 -275);
FORCEPROP 2 LAST ROOM IO_SLOT
J 1
(-925 -125);
DISPLAY 0.744681 (-925 -125);
DISPLAY INVISIBLE (-925 -125);
FORCEPROP 2 LAST CDS_LIB logical_power
J 0
(-700 -200);
PAINT MONO (-700 -200);
DISPLAY INVISIBLE (-700 -200);
FORCEPROP 1 LAST PATH I7
J 0
(-625 -200);
DISPLAY 0.872340 (-625 -200);
PAINT AQUA (-625 -200);
DISPLAY INVISIBLE (-625 -200);
FORCEADD OFFPAGE..2
(5250 375);
FORCEPROP 2 LAST $XR0 231 
J 0
(5439 375);
DISPLAY 0.638298 (5439 375);
PAINT MONO (5439 375);
FORCEPROP 2 LAST $XR1 227 
J 0
(5559 375);
DISPLAY 0.638298 (5559 375);
PAINT MONO (5559 375);
FORCEPROP 1 LAST COMMENT_BODY TRUE
J 0
(5205 280);
DISPLAY 0.872340 (5205 280);
PAINT GREEN (5205 280);
DISPLAY INVISIBLE (5205 280);
FORCEPROP 1 LAST OFFPAGE TRUE
J 0
(5575 250);
DISPLAY 0.872340 (5575 250);
PAINT GREEN (5575 250);
DISPLAY INVISIBLE (5575 250);
FORCEPROP 2 LAST CDS_LIB standard
J 0
(5250 375);
PAINT MONO (5250 375);
DISPLAY INVISIBLE (5250 375);
FORCEPROP 2 LAST PATH I70
J 0
(5575 425);
DISPLAY 1.021277 (5575 425);
DISPLAY INVISIBLE (5575 425);
FORCEADD OFFPAGE..2
(5250 650);
FORCEPROP 2 LAST $XR0 231 
J 0
(5439 650);
DISPLAY 0.638298 (5439 650);
PAINT MONO (5439 650);
FORCEPROP 2 LAST $XR1 232 
J 0
(5559 650);
DISPLAY 0.638298 (5559 650);
PAINT MONO (5559 650);
FORCEPROP 1 LAST COMMENT_BODY TRUE
J 0
(5205 555);
DISPLAY 0.872340 (5205 555);
PAINT GREEN (5205 555);
DISPLAY INVISIBLE (5205 555);
FORCEPROP 1 LAST OFFPAGE TRUE
J 0
(5575 525);
DISPLAY 0.872340 (5575 525);
PAINT GREEN (5575 525);
DISPLAY INVISIBLE (5575 525);
FORCEPROP 2 LAST CDS_LIB standard
J 0
(5250 650);
PAINT MONO (5250 650);
DISPLAY INVISIBLE (5250 650);
FORCEPROP 2 LAST PATH I71
J 0
(5575 700);
DISPLAY 1.021277 (5575 700);
DISPLAY INVISIBLE (5575 700);
FORCEADD OFFPAGE..2
(5250 600);
FORCEPROP 2 LAST $XR0 231 
J 0
(5439 600);
DISPLAY 0.638298 (5439 600);
PAINT MONO (5439 600);
FORCEPROP 2 LAST $XR1 232 
J 0
(5559 600);
DISPLAY 0.638298 (5559 600);
PAINT MONO (5559 600);
FORCEPROP 1 LAST COMMENT_BODY TRUE
J 0
(5205 505);
DISPLAY 0.872340 (5205 505);
PAINT GREEN (5205 505);
DISPLAY INVISIBLE (5205 505);
FORCEPROP 1 LAST OFFPAGE TRUE
J 0
(5575 475);
DISPLAY 0.872340 (5575 475);
PAINT GREEN (5575 475);
DISPLAY INVISIBLE (5575 475);
FORCEPROP 2 LAST CDS_LIB standard
J 0
(5250 600);
PAINT MONO (5250 600);
DISPLAY INVISIBLE (5250 600);
FORCEPROP 2 LAST PATH I72
J 0
(5575 650);
DISPLAY 1.021277 (5575 650);
DISPLAY INVISIBLE (5575 650);
FORCEADD OFFPAGE..2
(5250 975);
FORCEPROP 2 LAST $XR0 240 
J 0
(5439 975);
DISPLAY 0.638298 (5439 975);
PAINT MONO (5439 975);
FORCEPROP 2 LAST $XR1 231 
J 0
(5559 975);
DISPLAY 0.638298 (5559 975);
PAINT MONO (5559 975);
FORCEPROP 1 LAST COMMENT_BODY TRUE
J 0
(5205 880);
DISPLAY 0.872340 (5205 880);
PAINT GREEN (5205 880);
DISPLAY INVISIBLE (5205 880);
FORCEPROP 1 LAST OFFPAGE TRUE
J 0
(5575 850);
DISPLAY 0.872340 (5575 850);
PAINT GREEN (5575 850);
DISPLAY INVISIBLE (5575 850);
FORCEPROP 2 LAST CDS_LIB standard
J 0
(5250 975);
PAINT MONO (5250 975);
DISPLAY INVISIBLE (5250 975);
FORCEPROP 2 LAST PATH I73
J 0
(5575 1025);
DISPLAY 1.021277 (5575 1025);
DISPLAY INVISIBLE (5575 1025);
FORCEADD OFFPAGE..2
(5250 1025);
FORCEPROP 2 LAST $XR0 231 
J 0
(5439 1025);
DISPLAY 0.638298 (5439 1025);
PAINT MONO (5439 1025);
FORCEPROP 2 LAST $XR1 240 
J 0
(5559 1025);
DISPLAY 0.638298 (5559 1025);
PAINT MONO (5559 1025);
FORCEPROP 1 LAST COMMENT_BODY TRUE
J 0
(5205 930);
DISPLAY 0.872340 (5205 930);
PAINT GREEN (5205 930);
DISPLAY INVISIBLE (5205 930);
FORCEPROP 1 LAST OFFPAGE TRUE
J 0
(5575 900);
DISPLAY 0.872340 (5575 900);
PAINT GREEN (5575 900);
DISPLAY INVISIBLE (5575 900);
FORCEPROP 2 LAST CDS_LIB standard
J 0
(5250 1025);
PAINT MONO (5250 1025);
DISPLAY INVISIBLE (5250 1025);
FORCEPROP 2 LAST PATH I74
J 0
(5575 1075);
DISPLAY 1.021277 (5575 1075);
DISPLAY INVISIBLE (5575 1075);
FORCEADD OFFPAGE..5
R 2
(4600 2525);
FORCEPROP 2 LAST $XR0 231 
J 0
(4819 2525);
DISPLAY 0.638298 (4819 2525);
PAINT MONO (4819 2525);
FORCEPROP 2 LAST $XR1 232 
J 0
(4939 2525);
DISPLAY 0.638298 (4939 2525);
PAINT MONO (4939 2525);
FORCEPROP 1 LAST COMMENT_BODY TRUE
J 2
(4500 2450);
DISPLAY 0.872340 (4500 2450);
PAINT GREEN (4500 2450);
DISPLAY INVISIBLE (4500 2450);
FORCEPROP 1 LAST OFFPAGE TRUE
J 2
(4275 2400);
DISPLAY 0.872340 (4275 2400);
DISPLAY INVISIBLE (4275 2400);
FORCEPROP 2 LAST CDS_LIB standard
J 0
(4600 2525);
DISPLAY INVISIBLE (4600 2525);
FORCEPROP 2 LAST PATH I75
J 0
(4950 2575);
DISPLAY 1.021277 (4950 2575);
DISPLAY INVISIBLE (4950 2575);
FORCEADD OFFPAGE..3
(4600 2575);
FORCEPROP 2 LAST $XR0 231 
J 0
(4814 2575);
DISPLAY 0.638298 (4814 2575);
PAINT MONO (4814 2575);
FORCEPROP 2 LAST $XR1 232 
J 0
(4934 2575);
DISPLAY 0.638298 (4934 2575);
PAINT MONO (4934 2575);
FORCEPROP 1 LAST COMMENT_BODY TRUE
J 0
(4550 2475);
DISPLAY 0.872340 (4550 2475);
PAINT GREEN (4550 2475);
DISPLAY INVISIBLE (4550 2475);
FORCEPROP 1 LAST OFFPAGE TRUE
J 0
(4925 2450);
DISPLAY 0.872340 (4925 2450);
DISPLAY INVISIBLE (4925 2450);
FORCEPROP 2 LAST CDS_LIB standard
J 0
(4600 2575);
DISPLAY INVISIBLE (4600 2575);
FORCEPROP 2 LAST PATH I76
J 0
(4950 2625);
DISPLAY 1.021277 (4950 2625);
DISPLAY INVISIBLE (4950 2625);
FORCEADD OFFPAGE..3
(4600 2675);
FORCEPROP 2 LAST $XR0 231 
J 0
(4814 2675);
DISPLAY 0.638298 (4814 2675);
PAINT MONO (4814 2675);
FORCEPROP 2 LAST $XR1 243 
J 0
(4934 2675);
DISPLAY 0.638298 (4934 2675);
PAINT MONO (4934 2675);
FORCEPROP 1 LAST COMMENT_BODY TRUE
J 0
(4550 2575);
DISPLAY 0.872340 (4550 2575);
PAINT GREEN (4550 2575);
DISPLAY INVISIBLE (4550 2575);
FORCEPROP 1 LAST OFFPAGE TRUE
J 0
(4925 2550);
DISPLAY 0.872340 (4925 2550);
DISPLAY INVISIBLE (4925 2550);
FORCEPROP 2 LAST CDS_LIB standard
J 0
(4600 2675);
DISPLAY INVISIBLE (4600 2675);
FORCEPROP 2 LAST PATH I77
J 0
(4950 2725);
DISPLAY 1.021277 (4950 2725);
DISPLAY INVISIBLE (4950 2725);
FORCEADD OFFPAGE..5
R 2
(4600 2625);
FORCEPROP 2 LAST $XR0 231 
J 0
(4819 2625);
DISPLAY 0.638298 (4819 2625);
PAINT MONO (4819 2625);
FORCEPROP 2 LAST $XR1 243 
J 0
(4939 2625);
DISPLAY 0.638298 (4939 2625);
PAINT MONO (4939 2625);
FORCEPROP 1 LAST COMMENT_BODY TRUE
J 2
(4500 2550);
DISPLAY 0.872340 (4500 2550);
PAINT GREEN (4500 2550);
DISPLAY INVISIBLE (4500 2550);
FORCEPROP 1 LAST OFFPAGE TRUE
J 2
(4275 2500);
DISPLAY 0.872340 (4275 2500);
DISPLAY INVISIBLE (4275 2500);
FORCEPROP 2 LAST CDS_LIB standard
J 0
(4600 2625);
DISPLAY INVISIBLE (4600 2625);
FORCEPROP 2 LAST PATH I78
J 0
(4950 2675);
DISPLAY 1.021277 (4950 2675);
DISPLAY INVISIBLE (4950 2675);
FORCEADD OFFPAGE..3
(4600 2775);
FORCEPROP 2 LAST $XR0 231 
J 0
(4814 2775);
DISPLAY 0.638298 (4814 2775);
PAINT MONO (4814 2775);
FORCEPROP 2 LAST $XR1 234 
J 0
(4934 2775);
DISPLAY 0.638298 (4934 2775);
PAINT MONO (4934 2775);
FORCEPROP 1 LAST COMMENT_BODY TRUE
J 0
(4550 2675);
DISPLAY 0.872340 (4550 2675);
PAINT GREEN (4550 2675);
DISPLAY INVISIBLE (4550 2675);
FORCEPROP 1 LAST OFFPAGE TRUE
J 0
(4925 2650);
DISPLAY 0.872340 (4925 2650);
DISPLAY INVISIBLE (4925 2650);
FORCEPROP 2 LAST CDS_LIB standard
J 0
(4600 2775);
DISPLAY INVISIBLE (4600 2775);
FORCEPROP 2 LAST PATH I79
J 0
(4950 2825);
DISPLAY 1.021277 (4950 2825);
DISPLAY INVISIBLE (4950 2825);
FORCEADD Q_RES..2
(-700 25);
FORCEPROP 1 LAST PART_NUMBER CS21002FB06
J 0
(-660 -100);
DISPLAY 0.510638 (-660 -100);
DISPLAY INVISIBLE (-660 -100);
FORCEPROP 1 LAST TOLERANCE 1%
J 0
(-655 50);
DISPLAY 0.638298 (-655 50);
FORCEPROP 1 LAST PACK_TYPE 0402LF
J 0
(-660 -150);
DISPLAY 0.638298 (-660 -150);
FORCEPROP 1 LAST VALUE 1K
J 0
(-655 100);
DISPLAY 0.638298 (-655 100);
FORCEPROP 1 LAST MATERIAL CHIP
J 0
(-660 -50);
DISPLAY 0.638298 (-660 -50);
FORCEPROP 1 LAST WATTAGE 1/16W
J 0
(-660 0);
DISPLAY 0.638298 (-660 0);
FORCEPROP 1 LAST $LOCATION R587
J 0
(-655 150);
DISPLAY 0.978723 (-655 150);
FORCEPROP 1 LASTPIN (-700 125) $PN 1
J 0
(-695 87);
DISPLAY 0.787234 (-695 87);
FORCEPROP 1 LASTPIN (-700 -75) $PN 2
J 0
(-695 -65);
DISPLAY 0.787234 (-695 -65);
FORCEPROP 2 LAST CDS_LIB pure_quanta
J 0
(-700 25);
PAINT MONO (-700 25);
DISPLAY INVISIBLE (-700 25);
FORCEPROP 1 LAST PATH I8
J 0
(-650 200);
DISPLAY 0.978723 (-650 200);
PAINT WHITE (-650 200);
DISPLAY INVISIBLE (-650 200);
FORCEPROP 1 LAST $LOCATION R587
J 0
(-650 250);
DISPLAY 1.021277 (-650 250);
DISPLAY INVISIBLE (-650 250);
FORCEPROP 2 LAST CDS_LOCATION R587
J 0
(-650 250);
DISPLAY 1.021277 (-650 250);
DISPLAY INVISIBLE (-650 250);
FORCEPROP 2 LAST $SEC 1
J 0
(-650 250);
DISPLAY 0.680851 (-650 250);
PAINT MONO (-650 250);
DISPLAY INVISIBLE (-650 250);
FORCEPROP 2 LAST CDS_SEC 1
J 0
(-650 250);
DISPLAY 1.021277 (-650 250);
DISPLAY INVISIBLE (-650 250);
FORCEADD OFFPAGE..5
R 2
(4600 2725);
FORCEPROP 2 LAST $XR0 231 
J 0
(4819 2725);
DISPLAY 0.638298 (4819 2725);
PAINT MONO (4819 2725);
FORCEPROP 2 LAST $XR1 234 
J 0
(4939 2725);
DISPLAY 0.638298 (4939 2725);
PAINT MONO (4939 2725);
FORCEPROP 1 LAST COMMENT_BODY TRUE
J 2
(4500 2650);
DISPLAY 0.872340 (4500 2650);
PAINT GREEN (4500 2650);
DISPLAY INVISIBLE (4500 2650);
FORCEPROP 1 LAST OFFPAGE TRUE
J 2
(4275 2600);
DISPLAY 0.872340 (4275 2600);
DISPLAY INVISIBLE (4275 2600);
FORCEPROP 2 LAST CDS_LIB standard
J 0
(4600 2725);
DISPLAY INVISIBLE (4600 2725);
FORCEPROP 2 LAST PATH I80
J 0
(4950 2775);
DISPLAY 1.021277 (4950 2775);
DISPLAY INVISIBLE (4950 2775);
FORCEADD OFFPAGE..3
(4600 2975);
FORCEPROP 2 LAST $XR0 231 
J 0
(4814 2975);
DISPLAY 0.638298 (4814 2975);
PAINT MONO (4814 2975);
FORCEPROP 2 LAST $XR1 240 
J 0
(4934 2975);
DISPLAY 0.638298 (4934 2975);
PAINT MONO (4934 2975);
FORCEPROP 1 LAST COMMENT_BODY TRUE
J 0
(4550 2875);
DISPLAY 0.872340 (4550 2875);
PAINT GREEN (4550 2875);
DISPLAY INVISIBLE (4550 2875);
FORCEPROP 1 LAST OFFPAGE TRUE
J 0
(4925 2850);
DISPLAY 0.872340 (4925 2850);
PAINT GREEN (4925 2850);
DISPLAY INVISIBLE (4925 2850);
FORCEPROP 2 LAST CDS_LIB standard
J 0
(4600 2975);
DISPLAY INVISIBLE (4600 2975);
FORCEPROP 2 LAST PATH I81
J 0
(4950 3025);
DISPLAY 1.021277 (4950 3025);
DISPLAY INVISIBLE (4950 3025);
FORCEADD OFFPAGE..4
(4600 3025);
FORCEPROP 2 LAST $XR0 231 
J 0
(4786 3025);
DISPLAY 0.638298 (4786 3025);
PAINT MONO (4786 3025);
FORCEPROP 2 LAST $XR1 240 
J 0
(4906 3025);
DISPLAY 0.638298 (4906 3025);
PAINT MONO (4906 3025);
FORCEPROP 1 LAST COMMENT_BODY TRUE
J 0
(4575 2925);
DISPLAY 0.872340 (4575 2925);
PAINT GREEN (4575 2925);
DISPLAY INVISIBLE (4575 2925);
FORCEPROP 1 LAST OFFPAGE TRUE
J 0
(4925 2900);
DISPLAY 0.872340 (4925 2900);
DISPLAY INVISIBLE (4925 2900);
FORCEPROP 2 LAST CDS_LIB standard
J 0
(4600 3025);
DISPLAY INVISIBLE (4600 3025);
FORCEPROP 2 LAST PATH I82
J 0
(4925 3075);
DISPLAY 1.021277 (4925 3075);
DISPLAY INVISIBLE (4925 3075);
FORCEADD Q_RES..2
(-975 675);
FORCEPROP 1 LAST PART_NUMBER CS31002FB08
J 0
(-935 550);
DISPLAY 0.510638 (-935 550);
DISPLAY INVISIBLE (-935 550);
FORCEPROP 1 LAST VALUE 10K
J 0
(-930 750);
DISPLAY 0.638298 (-930 750);
FORCEPROP 1 LAST WATTAGE 1/16W
J 0
(-935 650);
DISPLAY 0.638298 (-935 650);
FORCEPROP 1 LAST TOLERANCE 1%
J 0
(-930 700);
DISPLAY 0.638298 (-930 700);
FORCEPROP 1 LAST MATERIAL EMPTY
J 0
(-935 600);
DISPLAY 0.638298 (-935 600);
PAINT RED (-935 600);
FORCEPROP 1 LAST PACK_TYPE 0402LF
J 0
(-935 550);
DISPLAY 0.638298 (-935 550);
FORCEPROP 1 LAST $LOCATION R538
J 0
(-930 800);
DISPLAY 0.978723 (-930 800);
FORCEPROP 1 LASTPIN (-975 775) $PN 1
J 0
(-970 737);
DISPLAY 0.787234 (-970 737);
FORCEPROP 1 LASTPIN (-975 575) $PN 2
J 0
(-970 585);
DISPLAY 0.787234 (-970 585);
FORCEPROP 2 LAST CDS_LIB pure_quanta
J 0
(-975 675);
PAINT MONO (-975 675);
DISPLAY INVISIBLE (-975 675);
FORCEPROP 1 LAST PATH I9
J 0
(-925 850);
DISPLAY 0.978723 (-925 850);
PAINT WHITE (-925 850);
DISPLAY INVISIBLE (-925 850);
FORCEPROP 1 LAST $LOCATION R538
J 0
(-925 900);
DISPLAY 1.021277 (-925 900);
DISPLAY INVISIBLE (-925 900);
FORCEPROP 2 LAST CDS_LOCATION R538
J 0
(-925 900);
DISPLAY 1.021277 (-925 900);
DISPLAY INVISIBLE (-925 900);
FORCEPROP 2 LAST $SEC 1
J 0
(-925 900);
DISPLAY 0.680851 (-925 900);
PAINT MONO (-925 900);
DISPLAY INVISIBLE (-925 900);
FORCEPROP 2 LAST CDS_SEC 1
J 0
(-925 900);
DISPLAY 1.021277 (-925 900);
DISPLAY INVISIBLE (-925 900);
FORCEADD DNS..2
(-1245 645);
PAINT RED (-1245 645);
FORCEPROP 1 LAST COMMENT_BODY TRUE
J 0
(-1245 645);
DISPLAY INVISIBLE (-1245 645);
FORCEPROP 2 LAST CDS_LIB mstr_misc
J 0
(-1245 645);
PAINT MONO (-1245 645);
DISPLAY INVISIBLE (-1245 645);
FORCEADD DNS..2
(-970 645);
PAINT RED (-970 645);
FORCEPROP 1 LAST COMMENT_BODY TRUE
J 0
(-970 645);
DISPLAY INVISIBLE (-970 645);
FORCEPROP 2 LAST CDS_LIB mstr_misc
J 0
(-970 645);
PAINT MONO (-970 645);
DISPLAY INVISIBLE (-970 645);
FORCEADD DNS..2
(-695 645);
PAINT RED (-695 645);
FORCEPROP 1 LAST COMMENT_BODY TRUE
J 0
(-695 645);
DISPLAY INVISIBLE (-695 645);
FORCEPROP 2 LAST CDS_LIB mstr_misc
J 0
(-695 645);
PAINT MONO (-695 645);
DISPLAY INVISIBLE (-695 645);
FORCEADD DNS..2
(3875 975);
PAINT RED (3875 975);
FORCEPROP 1 LAST COMMENT_BODY TRUE
J 0
(3875 975);
DISPLAY INVISIBLE (3875 975);
FORCEPROP 2 LAST CDS_LIB mstr_misc
J 0
(3875 975);
DISPLAY INVISIBLE (3875 975);
FORCEADD DNS..2
(3875 1025);
PAINT RED (3875 1025);
FORCEPROP 1 LAST COMMENT_BODY TRUE
J 0
(3875 1025);
DISPLAY INVISIBLE (3875 1025);
FORCEPROP 2 LAST CDS_LIB mstr_misc
J 0
(3875 1025);
DISPLAY INVISIBLE (3875 1025);
FORCEADD QUANTA_TITLE_BLOCK_C..1
(6275 -2050);
FORCEPROP 0 LAST CDS_CON_LAST_MODIFIED Fri Aug 25 14:03:54 2023
J 0
(4390 -2035);
PAINT MONO (4390 -2035);
DISPLAY INVISIBLE (4390 -2035);
FORCEPROP 2 LAST CUSTOM_TXT_CDS <XR_PAGE_TITLE>
J 0
(-1615 3200);
DISPLAY 0.638298 (-1615 3200);
PAINT PINK (-1615 3200);
DISPLAY INVISIBLE (-1615 3200);
FORCEPROP 2 LAST CUSTOM_TXT_CDS <CON_LAST_MODIFIED>
J 0
(4390 -2035);
DISPLAY 0.978723 (4390 -2035);
FORCEPROP 2 LAST CUSTOM_TXT_CDS <NAME_2>
J 0
(3100 -2000);
FORCEPROP 2 LAST CUSTOM_TXT_CDS <NAME_1>
J 0
(3100 -1875);
FORCEPROP 2 LAST CUSTOM_TXT_CDS <Q_NUMBER>
J 0
(4872 -1947);
DISPLAY 1.212766 (4872 -1947);
FORCEPROP 2 LAST CUSTOM_TXT_CDS <Q_PROJ>
J 0
(3893 -1948);
DISPLAY 1.212766 (3893 -1948);
FORCEPROP 2 LAST CUSTOM_TXT_CDS <Q_REV>
J 0
(6091 -1947);
DISPLAY 1.212766 (6091 -1947);
FORCEPROP 2 LAST CUSTOM_TXT_CDS <CON_PAGE_NUM> OF <CON_TOTAL_PAGES>
J 0
(5829 -2032);
DISPLAY 0.978723 (5829 -2032);
FORCEPROP 1 LAST Q_TITLE SMBUS - PCIE0  SMBUS
J 0
(-2991 -2024);
DISPLAY 2.446809 (-2991 -2024);
PAINT GREEN (-2991 -2024);
FORCEPROP 1 LAST Q_DEPT 
J 1
(2512 -2001);
DISPLAY 1.957447 (2512 -2001);
PAINT GREEN (2512 -2001);
FORCEPROP 1 LAST COMMENT_BODY TRUE
J 0
(6287 -2063);
DISPLAY 0.978723 (6287 -2063);
PAINT GREEN (6287 -2063);
DISPLAY INVISIBLE (6287 -2063);
FORCEPROP 2 LAST CDS_LIB pure_quanta
J 0
(6275 -2050);
PAINT MONO (6275 -2050);
DISPLAY INVISIBLE (6275 -2050);
FORCEPROP 1 LAST CDS_LMAN_SYM_OUTLINE -9475,6775,100,-125
J 0
(6275 -2050);
DISPLAY 0.468085 (6275 -2050);
PAINT GREEN (6275 -2050);
DISPLAY INVISIBLE (6275 -2050);
FORCEPROP 2 LAST PAGE_BORDER TRUE
J 0
(-1615 3200);
DISPLAY 0.638298 (-1615 3200);
PAINT PINK (-1615 3200);
DISPLAY INVISIBLE (-1615 3200);
FORCEPROP 2 LAST CDS_XR_PAGE_TITLE CR-231 : @S9S_MB_2U_LIB.S9S_MB_2U(SCH_1):PAGE231
J 0
(-1615 3200);
DISPLAY 0.638298 (-1615 3200);
PAINT PINK (-1615 3200);
DISPLAY INVISIBLE (-1615 3200);
WIRE 16 -1 (-1250 925)(-1250 1000);
WIRE 16 -1 (-1250 925)(-975 925);
WIRE 16 -1 (-1250 775)(-1250 925);
WIRE 16 -1 (-600 3450)(-600 3325);
WIRE 16 -1 (1200 3775)(1200 3700);
WIRE 16 -1 (3425 1175)(3425 1025);
WIRE 16 -1 (-1250 -150)(-1250 -75);
WIRE 16 -1 (-975 -150)(-975 -75);
WIRE 16 -1 (-700 -150)(-700 -75);
WIRE 16 -1 (1200 3400)(1200 3325);
WIRE 16 -1 (2575 2325)(2575 2200);
WIRE 16 -1 (2575 2325)(2425 2325);
WIRE 16 -1 (3975 75)(5225 75);
FORCEPROP 0 LAST CDS_PHYS_NET_NAME SMB_SENSOR_E1S_3V3AUX_SCL
J 0
(4015 123);
PAINT MONO (4015 123);
DISPLAY INVISIBLE (4015 123);
FORCEPROP 2 LAST SIG_NAME SMB_SENSOR_E1S_3V3AUX_SCL
J 0
(4490 85);
DISPLAY 0.510638 (4490 85);
PAINT WHITE (4490 85);
WIRE 16 -1 (3975 25)(5225 25);
FORCEPROP 0 LAST CDS_PHYS_NET_NAME SMB_SENSOR_E1S_3V3AUX_SDA
J 0
(4015 73);
PAINT MONO (4015 73);
DISPLAY INVISIBLE (4015 73);
FORCEPROP 2 LAST SIG_NAME SMB_SENSOR_E1S_3V3AUX_SDA
J 0
(4490 35);
DISPLAY 0.510638 (4490 35);
PAINT WHITE (4490 35);
WIRE 16 -1 (5200 1025)(3950 1025);
FORCEPROP 0 LAST CDS_PHYS_NET_NAME SMB_PCIE0_3V3AUX_SCL
J 0
(4165 1073);
PAINT MONO (4165 1073);
DISPLAY INVISIBLE (4165 1073);
FORCEPROP 2 LAST SIG_NAME SMB_PCIE0_3V3AUX_SCL
J 0
(4465 1035);
DISPLAY 0.510638 (4465 1035);
PAINT WHITE (4465 1035);
WIRE 16 -1 (5200 975)(3950 975);
FORCEPROP 0 LAST CDS_PHYS_NET_NAME SMB_PCIE0_3V3AUX_SDA
J 0
(4165 1023);
PAINT MONO (4165 1023);
DISPLAY INVISIBLE (4165 1023);
FORCEPROP 2 LAST SIG_NAME SMB_PCIE0_3V3AUX_SDA
J 0
(4465 985);
DISPLAY 0.510638 (4465 985);
PAINT WHITE (4465 985);
WIRE 16 -1 (5200 650)(3950 650);
FORCEPROP 0 LAST CDS_PHYS_NET_NAME SMB_INA230_3V3AUX_SCL
J 0
(4165 698);
PAINT MONO (4165 698);
DISPLAY INVISIBLE (4165 698);
FORCEPROP 2 LAST SIG_NAME SMB_INA230_3V3AUX_SCL
J 0
(4465 660);
DISPLAY 0.510638 (4465 660);
PAINT WHITE (4465 660);
WIRE 16 -1 (3500 2575)(4550 2575);
FORCEPROP 0 LAST CDS_PHYS_NET_NAME SMB_INA230_3V3AUX_SDA
J 0
(3540 2623);
PAINT MONO (3540 2623);
DISPLAY INVISIBLE (3540 2623);
FORCEPROP 2 LAST SIG_NAME SMB_INA230_3V3AUX_SDA
J 0
(3890 2585);
DISPLAY 0.510638 (3890 2585);
PAINT WHITE (3890 2585);
WIRE 16 -1 (3500 2625)(4550 2625);
FORCEPROP 0 LAST CDS_PHYS_NET_NAME SMB_FRU_3V3AUX_SCL
J 0
(3540 2673);
PAINT MONO (3540 2673);
DISPLAY INVISIBLE (3540 2673);
FORCEPROP 2 LAST SIG_NAME SMB_FRU_3V3AUX_SCL
J 0
(3890 2635);
DISPLAY 0.510638 (3890 2635);
PAINT WHITE (3890 2635);
WIRE 16 -1 (3500 2675)(4550 2675);
FORCEPROP 0 LAST CDS_PHYS_NET_NAME SMB_FRU_3V3AUX_SDA
J 0
(3540 2723);
PAINT MONO (3540 2723);
DISPLAY INVISIBLE (3540 2723);
FORCEPROP 2 LAST SIG_NAME SMB_FRU_3V3AUX_SDA
J 0
(3890 2685);
DISPLAY 0.510638 (3890 2685);
PAINT WHITE (3890 2685);
WIRE 16 -1 (4550 2725)(3500 2725);
FORCEPROP 0 LAST CDS_PHYS_NET_NAME SMB_BMC_SWB_SCL
J 0
(2340 2773);
PAINT MONO (2340 2773);
DISPLAY INVISIBLE (2340 2773);
FORCEPROP 2 LAST SIG_NAME SMB_BMC_SWB_SCL
J 0
(3890 2735);
DISPLAY 0.510638 (3890 2735);
PAINT WHITE (3890 2735);
WIRE 16 -1 (3500 2525)(4550 2525);
FORCEPROP 0 LAST CDS_PHYS_NET_NAME SMB_INA230_3V3AUX_SCL
J 0
(3540 2573);
PAINT MONO (3540 2573);
DISPLAY INVISIBLE (3540 2573);
FORCEPROP 2 LAST SIG_NAME SMB_INA230_3V3AUX_SCL
J 0
(3890 2535);
DISPLAY 0.510638 (3890 2535);
PAINT WHITE (3890 2535);
WIRE 16 -1 (3575 3025)(4550 3025);
FORCEPROP 0 LAST CDS_PHYS_NET_NAME SMB_PCIE0_3V3AUX_SDA
J 0
(3615 3073);
PAINT MONO (3615 3073);
DISPLAY INVISIBLE (3615 3073);
FORCEPROP 2 LAST SIG_NAME SMB_PCIE0_3V3AUX_SDA
J 0
(3890 3035);
DISPLAY 0.510638 (3890 3035);
PAINT WHITE (3890 3035);
WIRE 16 -1 (3575 2975)(4550 2975);
FORCEPROP 0 LAST CDS_PHYS_NET_NAME SMB_PCIE0_3V3AUX_SCL
J 0
(3615 3023);
PAINT MONO (3615 3023);
DISPLAY INVISIBLE (3615 3023);
FORCEPROP 2 LAST SIG_NAME SMB_PCIE0_3V3AUX_SCL
J 0
(3890 2985);
DISPLAY 0.510638 (3890 2985);
PAINT WHITE (3890 2985);
WIRE 16 -1 (4550 2775)(3500 2775);
FORCEPROP 0 LAST CDS_PHYS_NET_NAME SMB_BMC_SWB_SDA
J 0
(2340 2823);
PAINT MONO (2340 2823);
DISPLAY INVISIBLE (2340 2823);
FORCEPROP 2 LAST SIG_NAME SMB_BMC_SWB_SDA
J 0
(3890 2785);
DISPLAY 0.510638 (3890 2785);
PAINT WHITE (3890 2785);
WIRE 16 -1 (5200 325)(3950 325);
FORCEPROP 0 LAST CDS_PHYS_NET_NAME SMB_IOEXP_3V3AUX_SDA
J 0
(4165 373);
PAINT MONO (4165 373);
DISPLAY INVISIBLE (4165 373);
FORCEPROP 2 LAST SIG_NAME SMB_IOEXP_3V3AUX_SDA
J 0
(4465 335);
DISPLAY 0.510638 (4465 335);
PAINT WHITE (4465 335);
WIRE 16 -1 (5200 375)(3950 375);
FORCEPROP 0 LAST CDS_PHYS_NET_NAME SMB_IOEXP_3V3AUX_SCL
J 0
(4165 423);
PAINT MONO (4165 423);
DISPLAY INVISIBLE (4165 423);
FORCEPROP 2 LAST SIG_NAME SMB_IOEXP_3V3AUX_SCL
J 0
(4465 385);
DISPLAY 0.510638 (4465 385);
PAINT WHITE (4465 385);
WIRE 16 -1 (5200 600)(3950 600);
FORCEPROP 0 LAST CDS_PHYS_NET_NAME SMB_INA230_3V3AUX_SDA
J 0
(4165 648);
PAINT MONO (4165 648);
DISPLAY INVISIBLE (4165 648);
FORCEPROP 2 LAST SIG_NAME SMB_INA230_3V3AUX_SDA
J 0
(4465 610);
DISPLAY 0.510638 (4465 610);
PAINT WHITE (4465 610);
WIRE 16 -1 (3300 2575)(2425 2575);
FORCEPROP 0 LAST CDS_PHYS_NET_NAME SMB_INA230_3V3AUX_SDA_R
J 0
(2465 2623);
PAINT MONO (2465 2623);
DISPLAY INVISIBLE (2465 2623);
FORCEPROP 2 LAST SIG_NAME SMB_INA230_3V3AUX_SDA_R
J 0
(2590 2585);
DISPLAY 0.510638 (2590 2585);
PAINT WHITE (2590 2585);
WIRE 16 -1 (3300 2675)(2425 2675);
FORCEPROP 0 LAST CDS_PHYS_NET_NAME SMB_FRU_3V3AUX_SDA_R
J 0
(2465 2723);
PAINT MONO (2465 2723);
DISPLAY INVISIBLE (2465 2723);
FORCEPROP 2 LAST SIG_NAME SMB_FRU_3V3AUX_SDA_R
J 0
(2590 2685);
DISPLAY 0.510638 (2590 2685);
PAINT WHITE (2590 2685);
WIRE 16 -1 (3300 2625)(2425 2625);
FORCEPROP 0 LAST CDS_PHYS_NET_NAME SMB_FRU_3V3AUX_SCL_R
J 0
(2465 2673);
PAINT MONO (2465 2673);
DISPLAY INVISIBLE (2465 2673);
FORCEPROP 2 LAST SIG_NAME SMB_FRU_3V3AUX_SCL_R
J 0
(2590 2635);
DISPLAY 0.510638 (2590 2635);
PAINT WHITE (2590 2635);
WIRE 16 -1 (2425 2725)(3300 2725);
FORCEPROP 0 LAST CDS_PHYS_NET_NAME SMB_BMC_SWB_SCL_R4
J 0
(2465 2773);
PAINT MONO (2465 2773);
DISPLAY INVISIBLE (2465 2773);
FORCEPROP 2 LAST SIG_NAME SMB_BMC_SWB_SCL_R4
J 0
(2590 2735);
DISPLAY 0.510638 (2590 2735);
PAINT WHITE (2590 2735);
WIRE 16 -1 (2425 2775)(3300 2775);
FORCEPROP 0 LAST CDS_PHYS_NET_NAME SMB_BMC_SWB_SDA_R4
J 0
(2465 2823);
PAINT MONO (2465 2823);
DISPLAY INVISIBLE (2465 2823);
FORCEPROP 2 LAST SIG_NAME SMB_BMC_SWB_SDA_R4
J 0
(2590 2785);
DISPLAY 0.510638 (2590 2785);
PAINT WHITE (2590 2785);
WIRE 16 -1 (2425 3025)(3375 3025);
FORCEPROP 0 LAST CDS_PHYS_NET_NAME SMB_PCIE0_3V3AUX_SDA_R
J 0
(2465 3073);
PAINT MONO (2465 3073);
DISPLAY INVISIBLE (2465 3073);
FORCEPROP 2 LAST SIG_NAME SMB_PCIE0_3V3AUX_SDA_R
J 0
(2590 3035);
DISPLAY 0.510638 (2590 3035);
PAINT WHITE (2590 3035);
WIRE 16 -1 (3300 2525)(2425 2525);
FORCEPROP 0 LAST CDS_PHYS_NET_NAME SMB_INA230_3V3AUX_SCL_R
J 0
(2465 2573);
PAINT MONO (2465 2573);
DISPLAY INVISIBLE (2465 2573);
FORCEPROP 2 LAST SIG_NAME SMB_INA230_3V3AUX_SCL_R
J 0
(2590 2535);
DISPLAY 0.510638 (2590 2535);
PAINT WHITE (2590 2535);
WIRE 16 -1 (2425 2975)(3375 2975);
FORCEPROP 0 LAST CDS_PHYS_NET_NAME SMB_PCIE0_3V3AUX_SCL_R
J 0
(2465 3023);
PAINT MONO (2465 3023);
DISPLAY INVISIBLE (2465 3023);
FORCEPROP 2 LAST SIG_NAME SMB_PCIE0_3V3AUX_SCL_R
J 0
(2590 2985);
DISPLAY 0.510638 (2590 2985);
PAINT WHITE (2590 2985);
WIRE 16 -1 (3425 1025)(3750 1025);
WIRE 16 -1 (3425 975)(3750 975);
WIRE 16 -1 (3425 1025)(3425 975);
WIRE 16 -1 (3425 975)(3425 650);
WIRE 16 -1 (3425 650)(3750 650);
WIRE 16 -1 (3425 650)(3425 600);
WIRE 16 -1 (3425 600)(3750 600);
WIRE 16 -1 (3425 600)(3425 375);
WIRE 16 -1 (3425 375)(3750 375);
WIRE 16 -1 (3425 375)(3425 325);
WIRE 16 -1 (3425 325)(3750 325);
WIRE 16 -1 (3425 325)(3425 75);
WIRE 16 -1 (3425 75)(3775 75);
WIRE 16 -1 (3425 75)(3425 25);
WIRE 16 -1 (3425 25)(3775 25);
WIRE 16 -1 (3425 -575)(3775 -575);
WIRE 16 -1 (3425 25)(3425 -575);
WIRE 16 -1 (3425 -575)(3425 -625);
WIRE 16 -1 (3425 -625)(3775 -625);
WIRE 16 -1 (3425 -900)(3425 -625);
WIRE 16 -1 (3425 -900)(3775 -900);
WIRE 16 -1 (3425 -950)(3425 -900);
WIRE 16 -1 (3425 -950)(3775 -950);
WIRE 16 -1 (3425 -1225)(3775 -1225);
WIRE 16 -1 (3425 -1225)(3425 -950);
WIRE 16 -1 (3425 -1225)(3425 -1275);
WIRE 16 -1 (3425 -1275)(3775 -1275);
WIRE 16 -1 (1575 3175)(1725 3175);
WIRE 16 -1 (1575 3700)(1575 3175);
WIRE 16 -1 (1200 3700)(1575 3700);
WIRE 16 -1 (1200 3600)(1200 3700);
WIRE 16 -1 (1050 3075)(1725 3075);
FORCEPROP 2 LAST SIG_NAME PCA9548_PCIE3_ADDR0
J 0
(1090 3085);
DISPLAY 0.510638 (1090 3085);
PAINT WHITE (1090 3085);
WIRE 16 -1 (1050 3025)(1725 3025);
FORCEPROP 2 LAST SIG_NAME PCA9548_PCIE3_ADDR1
J 0
(1090 3035);
DISPLAY 0.510638 (1090 3035);
PAINT WHITE (1090 3035);
WIRE 16 -1 (1050 2975)(1725 2975);
FORCEPROP 0 LAST CDS_PHYS_NET_NAME PCA9548_PCIE3_ADDR2
J 0
(1090 3023);
PAINT MONO (1090 3023);
DISPLAY INVISIBLE (1090 3023);
FORCEPROP 2 LAST SIG_NAME PCA9548_PCIE3_ADDR2
J 0
(1090 2985);
DISPLAY 0.510638 (1090 2985);
PAINT WHITE (1090 2985);
WIRE 16 -1 (1725 2875)(600 2875);
FORCEPROP 0 LAST CDS_PHYS_NET_NAME PU_RST_SMB_PCIE0_N
J 0
(640 2923);
PAINT MONO (640 2923);
DISPLAY INVISIBLE (640 2923);
FORCEPROP 2 LAST SIG_NAME PU_RST_SMB_PCIE0_N
J 0
(1090 2885);
DISPLAY 0.510638 (1090 2885);
PAINT WHITE (1090 2885);
WIRE 16 -1 (1725 2675)(700 2675);
FORCEPROP 0 LAST CDS_PHYS_NET_NAME SMB_IOEXP_3V3AUX_SDA_R
J 0
(740 2723);
PAINT MONO (740 2723);
DISPLAY INVISIBLE (740 2723);
FORCEPROP 2 LAST SIG_NAME SMB_IOEXP_3V3AUX_SDA_R
J 0
(990 2685);
DISPLAY 0.510638 (990 2685);
PAINT WHITE (990 2685);
WIRE 16 -1 (1725 2625)(700 2625);
FORCEPROP 0 LAST CDS_PHYS_NET_NAME SMB_IOEXP_3V3AUX_SCL_R
J 0
(740 2673);
PAINT MONO (740 2673);
DISPLAY INVISIBLE (740 2673);
FORCEPROP 2 LAST SIG_NAME SMB_IOEXP_3V3AUX_SCL_R
J 0
(990 2635);
DISPLAY 0.510638 (990 2635);
PAINT WHITE (990 2635);
WIRE 16 -1 (700 2575)(1725 2575);
FORCEPROP 0 LAST CDS_PHYS_NET_NAME SMB_PCIE0_3V3AUX_SDA_R3
J 0
(740 2623);
PAINT MONO (740 2623);
DISPLAY INVISIBLE (740 2623);
FORCEPROP 2 LAST SIG_NAME SMB_PCIE0_3V3AUX_SDA_R3
J 0
(990 2585);
DISPLAY 0.510638 (990 2585);
PAINT WHITE (990 2585);
WIRE 16 -1 (700 2525)(1725 2525);
FORCEPROP 0 LAST CDS_PHYS_NET_NAME SMB_PCIE0_3V3AUX_SCL_R3
J 0
(740 2573);
PAINT MONO (740 2573);
DISPLAY INVISIBLE (740 2573);
FORCEPROP 2 LAST SIG_NAME SMB_PCIE0_3V3AUX_SCL_R3
J 0
(990 2535);
DISPLAY 0.510638 (990 2535);
PAINT WHITE (990 2535);
WIRE 16 -1 (700 2475)(1725 2475);
FORCEPROP 0 LAST CDS_PHYS_NET_NAME SMB_PCIE0_3V3AUX_SDA_R5
J 0
(740 2523);
PAINT MONO (740 2523);
DISPLAY INVISIBLE (740 2523);
FORCEPROP 2 LAST SIG_NAME SMB_PCIE0_3V3AUX_SDA_R5
J 0
(990 2485);
DISPLAY 0.510638 (990 2485);
PAINT WHITE (990 2485);
WIRE 16 -1 (700 2425)(1725 2425);
FORCEPROP 0 LAST CDS_PHYS_NET_NAME SMB_PCIE0_3V3AUX_SCL_R5
J 0
(740 2473);
PAINT MONO (740 2473);
DISPLAY INVISIBLE (740 2473);
FORCEPROP 2 LAST SIG_NAME SMB_PCIE0_3V3AUX_SCL_R5
J 0
(990 2435);
DISPLAY 0.510638 (990 2435);
PAINT WHITE (990 2435);
WIRE 16 -1 (3975 -1225)(5225 -1225);
FORCEPROP 0 LAST CDS_PHYS_NET_NAME SMB_SENSOR_M2_P0_3V3AUX_SCL
J 0
(4015 -1177);
PAINT MONO (4015 -1177);
DISPLAY INVISIBLE (4015 -1177);
FORCEPROP 2 LAST SIG_NAME SMB_SENSOR_M2_P0_3V3AUX_SCL
J 0
(4490 -1215);
DISPLAY 0.510638 (4490 -1215);
PAINT WHITE (4490 -1215);
WIRE 16 -1 (3975 -1275)(5225 -1275);
FORCEPROP 0 LAST CDS_PHYS_NET_NAME SMB_SENSOR_M2_P0_3V3AUX_SDA
J 0
(4015 -1227);
PAINT MONO (4015 -1227);
DISPLAY INVISIBLE (4015 -1227);
FORCEPROP 2 LAST SIG_NAME SMB_SENSOR_M2_P0_3V3AUX_SDA
J 0
(4490 -1265);
DISPLAY 0.510638 (4490 -1265);
PAINT WHITE (4490 -1265);
WIRE 16 -1 (5225 -950)(3975 -950);
FORCEPROP 0 LAST CDS_PHYS_NET_NAME SMB_FRU_3V3AUX_SDA
J 0
(4190 -902);
PAINT MONO (4190 -902);
DISPLAY INVISIBLE (4190 -902);
FORCEPROP 2 LAST SIG_NAME SMB_FRU_3V3AUX_SDA
J 0
(4490 -940);
DISPLAY 0.510638 (4490 -940);
PAINT WHITE (4490 -940);
WIRE 16 -1 (5225 -900)(3975 -900);
FORCEPROP 0 LAST CDS_PHYS_NET_NAME SMB_FRU_3V3AUX_SCL
J 0
(4190 -852);
PAINT MONO (4190 -852);
DISPLAY INVISIBLE (4190 -852);
FORCEPROP 2 LAST SIG_NAME SMB_FRU_3V3AUX_SCL
J 0
(4490 -890);
DISPLAY 0.510638 (4490 -890);
PAINT WHITE (4490 -890);
WIRE 16 -1 (5225 -575)(3975 -575);
FORCEPROP 0 LAST CDS_PHYS_NET_NAME SMB_BMC_SWB_SCL
J 0
(4190 -527);
PAINT MONO (4190 -527);
DISPLAY INVISIBLE (4190 -527);
FORCEPROP 2 LAST SIG_NAME SMB_BMC_SWB_SCL
J 0
(4490 -565);
DISPLAY 0.510638 (4490 -565);
PAINT WHITE (4490 -565);
WIRE 16 -1 (5225 -625)(3975 -625);
FORCEPROP 0 LAST CDS_PHYS_NET_NAME SMB_BMC_SWB_SDA
J 0
(4190 -577);
PAINT MONO (4190 -577);
DISPLAY INVISIBLE (4190 -577);
FORCEPROP 2 LAST SIG_NAME SMB_BMC_SWB_SDA
J 0
(4490 -615);
DISPLAY 0.510638 (4490 -615);
PAINT WHITE (4490 -615);
WIRE 16 2175 (3600 -675)(4300 -675);
WIRE 16 2175 (4300 -400)(4300 -675);
WIRE 16 2175 (3600 -400)(3600 -675);
WIRE 16 2175 (3600 -400)(4300 -400);
WIRE 16 -1 (500 2575)(-550 2575);
FORCEPROP 0 LAST CDS_PHYS_NET_NAME SMB_SENSOR_M2_P0_3V3AUX_SDA
J 0
(-1710 2623);
PAINT MONO (-1710 2623);
DISPLAY INVISIBLE (-1710 2623);
FORCEPROP 2 LAST SIG_NAME SMB_SENSOR_M2_P0_3V3AUX_SDA
J 0
(-435 2585);
DISPLAY 0.510638 (-435 2585);
PAINT WHITE (-435 2585);
WIRE 16 -1 (500 2525)(-550 2525);
FORCEPROP 0 LAST CDS_PHYS_NET_NAME SMB_SENSOR_M2_P0_3V3AUX_SCL
J 0
(-1710 2573);
PAINT MONO (-1710 2573);
DISPLAY INVISIBLE (-1710 2573);
FORCEPROP 2 LAST SIG_NAME SMB_SENSOR_M2_P0_3V3AUX_SCL
J 0
(-435 2535);
DISPLAY 0.510638 (-435 2535);
PAINT WHITE (-435 2535);
WIRE 16 -1 (500 2475)(-550 2475);
FORCEPROP 0 LAST CDS_PHYS_NET_NAME SMB_SENSOR_E1S_3V3AUX_SDA
J 0
(-1710 2523);
PAINT MONO (-1710 2523);
DISPLAY INVISIBLE (-1710 2523);
FORCEPROP 2 LAST SIG_NAME SMB_SENSOR_E1S_3V3AUX_SDA
J 0
(-435 2485);
DISPLAY 0.510638 (-435 2485);
PAINT WHITE (-435 2485);
WIRE 16 -1 (500 2425)(-550 2425);
FORCEPROP 0 LAST CDS_PHYS_NET_NAME SMB_SENSOR_E1S_3V3AUX_SCL
J 0
(-1710 2473);
PAINT MONO (-1710 2473);
DISPLAY INVISIBLE (-1710 2473);
FORCEPROP 2 LAST SIG_NAME SMB_SENSOR_E1S_3V3AUX_SCL
J 0
(-435 2435);
DISPLAY 0.510638 (-435 2435);
PAINT WHITE (-435 2435);
WIRE 16 -1 (-550 2675)(500 2675);
FORCEPROP 0 LAST CDS_PHYS_NET_NAME SMB_IOEXP_3V3AUX_SDA
J 0
(-510 2723);
PAINT MONO (-510 2723);
DISPLAY INVISIBLE (-510 2723);
FORCEPROP 2 LAST SIG_NAME SMB_IOEXP_3V3AUX_SDA
J 0
(-435 2685);
DISPLAY 0.510638 (-435 2685);
PAINT WHITE (-435 2685);
WIRE 16 -1 (-550 2625)(500 2625);
FORCEPROP 0 LAST CDS_PHYS_NET_NAME SMB_IOEXP_3V3AUX_SCL
J 0
(-510 2673);
PAINT MONO (-510 2673);
DISPLAY INVISIBLE (-510 2673);
FORCEPROP 2 LAST SIG_NAME SMB_IOEXP_3V3AUX_SCL
J 0
(-435 2635);
DISPLAY 0.510638 (-435 2635);
PAINT WHITE (-435 2635);
WIRE 16 -1 (-600 3125)(-600 2875);
WIRE 16 -1 (400 2875)(-600 2875);
WIRE 16 -1 (-1075 2875)(-600 2875);
FORCEPROP 0 LAST CDS_PHYS_NET_NAME RST_SMB_SWITCH_N
J 0
(-1035 2923);
PAINT MONO (-1035 2923);
DISPLAY INVISIBLE (-1035 2923);
FORCEPROP 2 LAST SIG_NAME RST_SMB_SWITCH_N
J 0
(-1060 2885);
DISPLAY 0.510638 (-1060 2885);
PAINT WHITE (-1060 2885);
WIRE 16 -1 (-975 775)(-975 925);
WIRE 16 -1 (-975 925)(-700 925);
WIRE 16 -1 (-700 775)(-700 925);
WIRE 16 -1 (-975 325)(-975 125);
WIRE 16 -1 (-975 575)(-975 325);
WIRE 16 -1 (-975 325)(375 325);
FORCEPROP 2 LAST SIG_NAME PCA9548_PCIE3_ADDR1
J 0
(-510 335);
DISPLAY 0.808511 (-510 335);
PAINT WHITE (-510 335);
WIRE 16 -1 (-700 250)(-700 125);
WIRE 16 -1 (-700 575)(-700 250);
WIRE 16 -1 (-700 250)(375 250);
FORCEPROP 2 LAST SIG_NAME PCA9548_PCIE3_ADDR0
J 0
(-510 260);
DISPLAY 0.808511 (-510 260);
PAINT WHITE (-510 260);
WIRE 16 -1 (-1250 400)(-1250 125);
WIRE 16 -1 (-1250 575)(-1250 400);
WIRE 16 -1 (-1250 400)(375 400);
FORCEPROP 2 LAST SIG_NAME PCA9548_PCIE3_ADDR2
J 0
(-510 410);
DISPLAY 0.808511 (-510 410);
PAINT WHITE (-510 410);
DOT 1 (-1250 400);
DOT 1 (-1250 925);
DOT 1 (-700 250);
DOT 1 (-975 325);
DOT 1 (-975 925);
DOT 1 (-600 2875);
DOT 1 (3425 -1225);
DOT 1 (3425 -900);
DOT 1 (3425 -950);
DOT 1 (3425 -625);
DOT 1 (3425 -575);
DOT 1 (1200 3700);
DOT 1 (3425 75);
DOT 1 (3425 25);
DOT 1 (3425 375);
DOT 1 (3425 325);
DOT 1 (3425 600);
DOT 1 (3425 650);
DOT 1 (3425 975);
DOT 1 (3425 1025);
FORCENOTE
PCA9546 ADDR: 0XE0
(-1625 -450) 0;
DISPLAY LEFT (-1625 -450);
DISPLAY 1.595745 (-1625 -450);
PAINT SKYBLUE (-1625 -450);
FORCENOTE
20210604 MODIFY FOR GT
(-2800 4350) 0;
DISPLAY LEFT (-2800 4350);
DISPLAY 2.510638 (-2800 4350);
PAINT PINK (-2800 4350);
FORCENOTE
20221222 CHANGE R2984,R2985 TO 10K OHM 
(3600 -375) 0;
DISPLAY LEFT (3600 -375);
DISPLAY 0.680851 (3600 -375);
PAINT WHITE (3600 -375);
QUIT
